G04 ================== begin FILE IDENTIFICATION RECORD ==================*
G04 Layout Name:  15669-1.brd*
G04 Film Name:    TMASK*
G04 File Format:  Gerber RS274X*
G04 File Origin:  Cadence Allegro 16.5-S056*
G04 Origin Date:  Wed Nov 16 04:08:14 2016*
G04 *
G04 Layer:  VIA CLASS/SOLDERMASK_TOP*
G04 Layer:  PIN/SOLDERMASK_TOP*
G04 Layer:  PACKAGE GEOMETRY/SOLDERMASK_TOP*
G04 Layer:  DRAWING FORMAT/LAYER_PCB_STORY*
G04 Layer:  DRAWING FORMAT/LAYER_SOLDER_T*
G04 Layer:  BOARD GEOMETRY/SOLDERMASK_TOP*
G04 *
G04 Offset:    (0.00 0.00)*
G04 Mirror:    No*
G04 Mode:      Positive*
G04 Rotation:  0*
G04 FullContactRelief:  No*
G04 UndefLineWidth:     6.00*
G04 ================== end FILE IDENTIFICATION RECORD ====================*
%FSLAX35Y35*MOIN*%
%IR0*IPPOS*OFA0.00000B0.00000*MIA0B0*SFA1.00000B1.00000*%
%AMMACRO65*
4,1,40,.013,.017,
-.013,.017,
-.013695,.016939,
-.014368,.016759,
-.015,.016464,
-.015571,.016064,
-.016064,.015571,
-.016464,.015,
-.016759,.014368,
-.016939,.013695,
-.017,.013,
-.017,-.013,
-.016939,-.013695,
-.016759,-.014368,
-.016464,-.015,
-.016064,-.015571,
-.015571,-.016064,
-.015,-.016464,
-.014368,-.016759,
-.013695,-.016939,
-.013,-.017,
.013,-.017,
.013695,-.016939,
.014368,-.016759,
.015,-.016464,
.015571,-.016064,
.016064,-.015571,
.016464,-.015,
.016759,-.014368,
.016939,-.013695,
.017,-.013,
.017,.013,
.016939,.013695,
.016759,.014368,
.016464,.015,
.016064,.015571,
.015571,.016064,
.015,.016464,
.014368,.016759,
.013695,.016939,
.013,.017,
0.0*
%
%ADD65MACRO65*%
%AMMACRO39*
4,1,40,.017,-.013,
.017,.013,
.016939,.013695,
.016759,.014368,
.016464,.015,
.016064,.015571,
.015571,.016064,
.015,.016464,
.014368,.016759,
.013695,.016939,
.013,.017,
-.013,.017,
-.013695,.016939,
-.014368,.016759,
-.015,.016464,
-.015571,.016064,
-.016064,.015571,
-.016464,.015,
-.016759,.014368,
-.016939,.013695,
-.017,.013,
-.017,-.013,
-.016939,-.013695,
-.016759,-.014368,
-.016464,-.015,
-.016064,-.015571,
-.015571,-.016064,
-.015,-.016464,
-.014368,-.016759,
-.013695,-.016939,
-.013,-.017,
.013,-.017,
.013695,-.016939,
.014368,-.016759,
.015,-.016464,
.015571,-.016064,
.016064,-.015571,
.016464,-.015,
.016759,-.014368,
.016939,-.013695,
.017,-.013,
0.0*
%
%ADD39MACRO39*%
%ADD36O,.103X.06*%
%ADD92R,.23X.032*%
%ADD38R,.11X.045*%
%ADD56R,.045X.11*%
%ADD18R,.11X.045*%
%ADD82R,.01X.007*%
%ADD29C,.02*%
%ADD60C,.032*%
%ADD17C,.016*%
%ADD13C,.034*%
%ADD11C,.08*%
%ADD37C,.073*%
%ADD16C,.028*%
%ADD10C,.086*%
%ADD85R,.062X.062*%
%AMMACRO42*
4,1,40,.0225,-.007,
.022378,-.008389,
.022018,-.009736,
.021428,-.011,
.020628,-.012142,
.019642,-.013128,
.0185,-.013928,
.017236,-.014518,
.015889,-.014878,
.0145,-.015,
-.0145,-.015,
-.015889,-.014878,
-.017236,-.014518,
-.0185,-.013928,
-.019642,-.013128,
-.020628,-.012142,
-.021428,-.011,
-.022018,-.009736,
-.022378,-.008389,
-.0225,-.007,
-.0225,.007,
-.022378,.008389,
-.022018,.009736,
-.021428,.011,
-.020628,.012142,
-.019642,.013128,
-.0185,.013928,
-.017236,.014518,
-.015889,.014878,
-.0145,.015,
.0145,.015,
.015889,.014878,
.017236,.014518,
.0185,.013928,
.019642,.013128,
.020628,.012142,
.021428,.011,
.022018,.009736,
.022378,.008389,
.0225,.007,
.0225,-.007,
0.0*
%
%ADD42MACRO42*%
%ADD14C,.087*%
%AMMACRO43*
4,1,40,-.007,-.0225,
-.008389,-.022378,
-.009736,-.022018,
-.011,-.021428,
-.012142,-.020628,
-.013128,-.019642,
-.013928,-.0185,
-.014518,-.017236,
-.014878,-.015889,
-.015,-.0145,
-.015,.0145,
-.014878,.015889,
-.014518,.017236,
-.013928,.0185,
-.013128,.019642,
-.012142,.020628,
-.011,.021428,
-.009736,.022018,
-.008389,.022378,
-.007,.0225,
.007,.0225,
.008389,.022378,
.009736,.022018,
.011,.021428,
.012142,.020628,
.013128,.019642,
.013928,.0185,
.014518,.017236,
.014878,.015889,
.015,.0145,
.015,-.0145,
.014878,-.015889,
.014518,-.017236,
.013928,-.0185,
.013128,-.019642,
.012142,-.020628,
.011,-.021428,
.009736,-.022018,
.008389,-.022378,
.007,-.0225,
-.007,-.0225,
0.0*
%
%ADD43MACRO43*%
%AMMACRO44*
4,1,40,.007,.011,
-.007,.011,
-.007695,.010939,
-.008368,.010759,
-.009,.010464,
-.009571,.010064,
-.010064,.009571,
-.010464,.009,
-.010759,.008368,
-.010939,.007695,
-.011,.007,
-.011,-.007,
-.010939,-.007695,
-.010759,-.008368,
-.010464,-.009,
-.010064,-.009571,
-.009571,-.010064,
-.009,-.010464,
-.008368,-.010759,
-.007695,-.010939,
-.007,-.011,
.007,-.011,
.007695,-.010939,
.008368,-.010759,
.009,-.010464,
.009571,-.010064,
.010064,-.009571,
.010464,-.009,
.010759,-.008368,
.010939,-.007695,
.011,-.007,
.011,.007,
.010939,.007695,
.010759,.008368,
.010464,.009,
.010064,.009571,
.009571,.010064,
.009,.010464,
.008368,.010759,
.007695,.010939,
.007,.011,
0.0*
%
%ADD44MACRO44*%
%AMMACRO30*
4,1,40,.011,-.007,
.011,.007,
.010939,.007695,
.010759,.008368,
.010464,.009,
.010064,.009571,
.009571,.010064,
.009,.010464,
.008368,.010759,
.007695,.010939,
.007,.011,
-.007,.011,
-.007695,.010939,
-.008368,.010759,
-.009,.010464,
-.009571,.010064,
-.010064,.009571,
-.010464,.009,
-.010759,.008368,
-.010939,.007695,
-.011,.007,
-.011,-.007,
-.010939,-.007695,
-.010759,-.008368,
-.010464,-.009,
-.010064,-.009571,
-.009571,-.010064,
-.009,-.010464,
-.008368,-.010759,
-.007695,-.010939,
-.007,-.011,
.007,-.011,
.007695,-.010939,
.008368,-.010759,
.009,-.010464,
.009571,-.010064,
.010064,-.009571,
.010464,-.009,
.010759,-.008368,
.010939,-.007695,
.011,-.007,
0.0*
%
%ADD30MACRO30*%
%AMMACRO25*
4,1,40,-.012,.008,
-.012,-.008,
-.011939,-.008695,
-.011759,-.009368,
-.011464,-.01,
-.011064,-.010571,
-.010571,-.011064,
-.01,-.011464,
-.009368,-.011759,
-.008695,-.011939,
-.008,-.012,
.008,-.012,
.008695,-.011939,
.009368,-.011759,
.01,-.011464,
.010571,-.011064,
.011064,-.010571,
.011464,-.01,
.011759,-.009368,
.011939,-.008695,
.012,-.008,
.012,.008,
.011939,.008695,
.011759,.009368,
.011464,.01,
.011064,.010571,
.010571,.011064,
.01,.011464,
.009368,.011759,
.008695,.011939,
.008,.012,
-.008,.012,
-.008695,.011939,
-.009368,.011759,
-.01,.011464,
-.010571,.011064,
-.011064,.010571,
-.011464,.01,
-.011759,.009368,
-.011939,.008695,
-.012,.008,
0.0*
%
%ADD25MACRO25*%
%ADD70R,.089X.089*%
%AMMACRO50*
4,1,40,.008,.012,
-.008,.012,
-.008695,.011939,
-.009368,.011759,
-.01,.011464,
-.010571,.011064,
-.011064,.010571,
-.011464,.01,
-.011759,.009368,
-.011939,.008695,
-.012,.008,
-.012,-.008,
-.011939,-.008695,
-.011759,-.009368,
-.011464,-.01,
-.011064,-.010571,
-.010571,-.011064,
-.01,-.011464,
-.009368,-.011759,
-.008695,-.011939,
-.008,-.012,
.008,-.012,
.008695,-.011939,
.009368,-.011759,
.01,-.011464,
.010571,-.011064,
.011064,-.010571,
.011464,-.01,
.011759,-.009368,
.011939,-.008695,
.012,-.008,
.012,.008,
.011939,.008695,
.011759,.009368,
.011464,.01,
.011064,.010571,
.010571,.011064,
.01,.011464,
.009368,.011759,
.008695,.011939,
.008,.012,
0.0*
%
%ADD50MACRO50*%
%AMMACRO26*
4,1,40,-.013,-.017,
.013,-.017,
.013695,-.016939,
.014368,-.016759,
.015,-.016464,
.015571,-.016064,
.016064,-.015571,
.016464,-.015,
.016759,-.014368,
.016939,-.013695,
.017,-.013,
.017,.013,
.016939,.013695,
.016759,.014368,
.016464,.015,
.016064,.015571,
.015571,.016064,
.015,.016464,
.014368,.016759,
.013695,.016939,
.013,.017,
-.013,.017,
-.013695,.016939,
-.014368,.016759,
-.015,.016464,
-.015571,.016064,
-.016064,.015571,
-.016464,.015,
-.016759,.014368,
-.016939,.013695,
-.017,.013,
-.017,-.013,
-.016939,-.013695,
-.016759,-.014368,
-.016464,-.015,
-.016064,-.015571,
-.015571,-.016064,
-.015,-.016464,
-.014368,-.016759,
-.013695,-.016939,
-.013,-.017,
0.0*
%
%ADD26MACRO26*%
%AMMACRO51*
4,1,40,-.017,.013,
-.017,-.013,
-.016939,-.013695,
-.016759,-.014368,
-.016464,-.015,
-.016064,-.015571,
-.015571,-.016064,
-.015,-.016464,
-.014368,-.016759,
-.013695,-.016939,
-.013,-.017,
.013,-.017,
.013695,-.016939,
.014368,-.016759,
.015,-.016464,
.015571,-.016064,
.016064,-.015571,
.016464,-.015,
.016759,-.014368,
.016939,-.013695,
.017,-.013,
.017,.013,
.016939,.013695,
.016759,.014368,
.016464,.015,
.016064,.015571,
.015571,.016064,
.015,.016464,
.014368,.016759,
.013695,.016939,
.013,.017,
-.013,.017,
-.013695,.016939,
-.014368,.016759,
-.015,.016464,
-.015571,.016064,
-.016064,.015571,
-.016464,.015,
-.016759,.014368,
-.016939,.013695,
-.017,.013,
0.0*
%
%ADD51MACRO51*%
%AMMACRO90*
4,1,6,.005,.0135,
.005,.0065,
.025,-.0135,
-.025,-.0135,
-.005,.0065,
-.005,.0135,
.005,.0135,
0.0*
%
%ADD90MACRO90*%
%AMMACRO45*
4,1,40,.007,.011,
-.007,.011,
-.007695,.010939,
-.008368,.010759,
-.009,.010464,
-.009571,.010064,
-.010064,.009571,
-.010464,.009,
-.010759,.008368,
-.010939,.007695,
-.011,.007,
-.011,-.007,
-.010939,-.007695,
-.010759,-.008368,
-.010464,-.009,
-.010064,-.009571,
-.009571,-.010064,
-.009,-.010464,
-.008368,-.010759,
-.007695,-.010939,
-.007,-.011,
.007,-.011,
.007695,-.010939,
.008368,-.010759,
.009,-.010464,
.009571,-.010064,
.010064,-.009571,
.010464,-.009,
.010759,-.008368,
.010939,-.007695,
.011,-.007,
.011,.007,
.010939,.007695,
.010759,.008368,
.010464,.009,
.010064,.009571,
.009571,.010064,
.009,.010464,
.008368,.010759,
.007695,.010939,
.007,.011,
0.0*
%
%ADD45MACRO45*%
%AMMACRO31*
4,1,40,.011,-.007,
.011,.007,
.010939,.007695,
.010759,.008368,
.010464,.009,
.010064,.009571,
.009571,.010064,
.009,.010464,
.008368,.010759,
.007695,.010939,
.007,.011,
-.007,.011,
-.007695,.010939,
-.008368,.010759,
-.009,.010464,
-.009571,.010064,
-.010064,.009571,
-.010464,.009,
-.010759,.008368,
-.010939,.007695,
-.011,.007,
-.011,-.007,
-.010939,-.007695,
-.010759,-.008368,
-.010464,-.009,
-.010064,-.009571,
-.009571,-.010064,
-.009,-.010464,
-.008368,-.010759,
-.007695,-.010939,
-.007,-.011,
.007,-.011,
.007695,-.010939,
.008368,-.010759,
.009,-.010464,
.009571,-.010064,
.010064,-.009571,
.010464,-.009,
.010759,-.008368,
.010939,-.007695,
.011,-.007,
0.0*
%
%ADD31MACRO31*%
%AMMACRO24*
4,1,40,-.012,.008,
-.012,-.008,
-.011939,-.008695,
-.011759,-.009368,
-.011464,-.01,
-.011064,-.010571,
-.010571,-.011064,
-.01,-.011464,
-.009368,-.011759,
-.008695,-.011939,
-.008,-.012,
.008,-.012,
.008695,-.011939,
.009368,-.011759,
.01,-.011464,
.010571,-.011064,
.011064,-.010571,
.011464,-.01,
.011759,-.009368,
.011939,-.008695,
.012,-.008,
.012,.008,
.011939,.008695,
.011759,.009368,
.011464,.01,
.011064,.010571,
.010571,.011064,
.01,.011464,
.009368,.011759,
.008695,.011939,
.008,.012,
-.008,.012,
-.008695,.011939,
-.009368,.011759,
-.01,.011464,
-.010571,.011064,
-.011064,.010571,
-.011464,.01,
-.011759,.009368,
-.011939,.008695,
-.012,.008,
0.0*
%
%ADD24MACRO24*%
%AMMACRO49*
4,1,40,.008,.012,
-.008,.012,
-.008695,.011939,
-.009368,.011759,
-.01,.011464,
-.010571,.011064,
-.011064,.010571,
-.011464,.01,
-.011759,.009368,
-.011939,.008695,
-.012,.008,
-.012,-.008,
-.011939,-.008695,
-.011759,-.009368,
-.011464,-.01,
-.011064,-.010571,
-.010571,-.011064,
-.01,-.011464,
-.009368,-.011759,
-.008695,-.011939,
-.008,-.012,
.008,-.012,
.008695,-.011939,
.009368,-.011759,
.01,-.011464,
.010571,-.011064,
.011064,-.010571,
.011464,-.01,
.011759,-.009368,
.011939,-.008695,
.012,-.008,
.012,.008,
.011939,.008695,
.011759,.009368,
.011464,.01,
.011064,.010571,
.010571,.011064,
.01,.011464,
.009368,.011759,
.008695,.011939,
.008,.012,
0.0*
%
%ADD49MACRO49*%
%AMMACRO27*
4,1,40,-.013,-.017,
.013,-.017,
.013695,-.016939,
.014368,-.016759,
.015,-.016464,
.015571,-.016064,
.016064,-.015571,
.016464,-.015,
.016759,-.014368,
.016939,-.013695,
.017,-.013,
.017,.013,
.016939,.013695,
.016759,.014368,
.016464,.015,
.016064,.015571,
.015571,.016064,
.015,.016464,
.014368,.016759,
.013695,.016939,
.013,.017,
-.013,.017,
-.013695,.016939,
-.014368,.016759,
-.015,.016464,
-.015571,.016064,
-.016064,.015571,
-.016464,.015,
-.016759,.014368,
-.016939,.013695,
-.017,.013,
-.017,-.013,
-.016939,-.013695,
-.016759,-.014368,
-.016464,-.015,
-.016064,-.015571,
-.015571,-.016064,
-.015,-.016464,
-.014368,-.016759,
-.013695,-.016939,
-.013,-.017,
0.0*
%
%ADD27MACRO27*%
%AMMACRO59*
4,1,40,-.017,.013,
-.017,-.013,
-.016939,-.013695,
-.016759,-.014368,
-.016464,-.015,
-.016064,-.015571,
-.015571,-.016064,
-.015,-.016464,
-.014368,-.016759,
-.013695,-.016939,
-.013,-.017,
.013,-.017,
.013695,-.016939,
.014368,-.016759,
.015,-.016464,
.015571,-.016064,
.016064,-.015571,
.016464,-.015,
.016759,-.014368,
.016939,-.013695,
.017,-.013,
.017,.013,
.016939,.013695,
.016759,.014368,
.016464,.015,
.016064,.015571,
.015571,.016064,
.015,.016464,
.014368,.016759,
.013695,.016939,
.013,.017,
-.013,.017,
-.013695,.016939,
-.014368,.016759,
-.015,.016464,
-.015571,.016064,
-.016064,.015571,
-.016464,.015,
-.016759,.014368,
-.016939,.013695,
-.017,.013,
0.0*
%
%ADD59MACRO59*%
%ADD74R,.042X.012*%
%ADD73R,.012X.042*%
%ADD58R,.022X.04*%
%ADD77R,.012X.06*%
%ADD69R,.012X.042*%
%ADD68R,.042X.012*%
%ADD61R,.06X.014*%
%ADD86R,.105X.128*%
%ADD76R,.014X.06*%
%ADD72R,.036X.012*%
%ADD71R,.012X.036*%
%ADD84R,.012X.037*%
%ADD83R,.037X.012*%
%ADD80R,.012X.046*%
%ADD79R,.046X.012*%
%ADD67R,.012X.036*%
%ADD66R,.036X.012*%
%AMMACRO75*
4,1,40,-.004,-.007,
.004,-.007,
.004347,-.00697,
.004684,-.006879,
.005,-.006732,
.005286,-.006532,
.005532,-.006286,
.005732,-.006,
.005879,-.005684,
.00597,-.005347,
.006,-.005,
.006,.005,
.00597,.005347,
.005879,.005684,
.005732,.006,
.005532,.006286,
.005286,.006532,
.005,.006732,
.004684,.006879,
.004347,.00697,
.004,.007,
-.004,.007,
-.004347,.00697,
-.004684,.006879,
-.005,.006732,
-.005286,.006532,
-.005532,.006286,
-.005732,.006,
-.005879,.005684,
-.00597,.005347,
-.006,.005,
-.006,-.005,
-.00597,-.005347,
-.005879,-.005684,
-.005732,-.006,
-.005532,-.006286,
-.005286,-.006532,
-.005,-.006732,
-.004684,-.006879,
-.004347,-.00697,
-.004,-.007,
0.0*
%
%ADD75MACRO75*%
%ADD81R,.05X.065*%
%ADD41R,.036X.024*%
%ADD88R,.065X.05*%
%ADD35R,.081X.026*%
%ADD55R,.065X.025*%
%ADD34R,.079X.02*%
%ADD19C,.315*%
%ADD54R,.045X.055*%
%ADD48R,.048X.016*%
%ADD15R,.098X.02*%
%ADD91C,.146*%
%ADD63R,.055X.045*%
%ADD62R,.016X.048*%
%ADD28R,.047X.073*%
%ADD57R,.073X.047*%
%ADD78R,.241X.241*%
%AMMACRO87*
4,1,40,.014,.008,
.014,-.008,
.013939,-.008695,
.013759,-.009368,
.013464,-.01,
.013064,-.010571,
.012571,-.011064,
.012,-.011464,
.011368,-.011759,
.010695,-.011939,
.01,-.012,
-.01,-.012,
-.010695,-.011939,
-.011368,-.011759,
-.012,-.011464,
-.012571,-.011064,
-.013064,-.010571,
-.013464,-.01,
-.013759,-.009368,
-.013939,-.008695,
-.014,-.008,
-.014,.008,
-.013939,.008695,
-.013759,.009368,
-.013464,.01,
-.013064,.010571,
-.012571,.011064,
-.012,.011464,
-.011368,.011759,
-.010695,.011939,
-.01,.012,
.01,.012,
.010695,.011939,
.011368,.011759,
.012,.011464,
.012571,.011064,
.013064,.010571,
.013464,.01,
.013759,.009368,
.013939,.008695,
.014,.008,
0.0*
%
%ADD87MACRO87*%
%AMMACRO53*
4,1,40,-.0225,.007,
-.022378,.008389,
-.022018,.009736,
-.021428,.011,
-.020628,.012142,
-.019642,.013128,
-.0185,.013928,
-.017236,.014518,
-.015889,.014878,
-.0145,.015,
.0145,.015,
.015889,.014878,
.017236,.014518,
.0185,.013928,
.019642,.013128,
.020628,.012142,
.021428,.011,
.022018,.009736,
.022378,.008389,
.0225,.007,
.0225,-.007,
.022378,-.008389,
.022018,-.009736,
.021428,-.011,
.020628,-.012142,
.019642,-.013128,
.0185,-.013928,
.017236,-.014518,
.015889,-.014878,
.0145,-.015,
-.0145,-.015,
-.015889,-.014878,
-.017236,-.014518,
-.0185,-.013928,
-.019642,-.013128,
-.020628,-.012142,
-.021428,-.011,
-.022018,-.009736,
-.022378,-.008389,
-.0225,-.007,
-.0225,.007,
0.0*
%
%ADD53MACRO53*%
%AMMACRO52*
4,1,40,.007,.0225,
.008389,.022378,
.009736,.022018,
.011,.021428,
.012142,.020628,
.013128,.019642,
.013928,.0185,
.014518,.017236,
.014878,.015889,
.015,.0145,
.015,-.0145,
.014878,-.015889,
.014518,-.017236,
.013928,-.0185,
.013128,-.019642,
.012142,-.020628,
.011,-.021428,
.009736,-.022018,
.008389,-.022378,
.007,-.0225,
-.007,-.0225,
-.008389,-.022378,
-.009736,-.022018,
-.011,-.021428,
-.012142,-.020628,
-.013128,-.019642,
-.013928,-.0185,
-.014518,-.017236,
-.014878,-.015889,
-.015,-.0145,
-.015,.0145,
-.014878,.015889,
-.014518,.017236,
-.013928,.0185,
-.013128,.019642,
-.012142,.020628,
-.011,.021428,
-.009736,.022018,
-.008389,.022378,
-.007,.0225,
.007,.0225,
0.0*
%
%ADD52MACRO52*%
%AMMACRO32*
4,1,40,-.007,-.011,
.007,-.011,
.007695,-.010939,
.008368,-.010759,
.009,-.010464,
.009571,-.010064,
.010064,-.009571,
.010464,-.009,
.010759,-.008368,
.010939,-.007695,
.011,-.007,
.011,.007,
.010939,.007695,
.010759,.008368,
.010464,.009,
.010064,.009571,
.009571,.010064,
.009,.010464,
.008368,.010759,
.007695,.010939,
.007,.011,
-.007,.011,
-.007695,.010939,
-.008368,.010759,
-.009,.010464,
-.009571,.010064,
-.010064,.009571,
-.010464,.009,
-.010759,.008368,
-.010939,.007695,
-.011,.007,
-.011,-.007,
-.010939,-.007695,
-.010759,-.008368,
-.010464,-.009,
-.010064,-.009571,
-.009571,-.010064,
-.009,-.010464,
-.008368,-.010759,
-.007695,-.010939,
-.007,-.011,
0.0*
%
%ADD32MACRO32*%
%AMMACRO23*
4,1,40,.012,-.008,
.012,.008,
.011939,.008695,
.011759,.009368,
.011464,.01,
.011064,.010571,
.010571,.011064,
.01,.011464,
.009368,.011759,
.008695,.011939,
.008,.012,
-.008,.012,
-.008695,.011939,
-.009368,.011759,
-.01,.011464,
-.010571,.011064,
-.011064,.010571,
-.011464,.01,
-.011759,.009368,
-.011939,.008695,
-.012,.008,
-.012,-.008,
-.011939,-.008695,
-.011759,-.009368,
-.011464,-.01,
-.011064,-.010571,
-.010571,-.011064,
-.01,-.011464,
-.009368,-.011759,
-.008695,-.011939,
-.008,-.012,
.008,-.012,
.008695,-.011939,
.009368,-.011759,
.01,-.011464,
.010571,-.011064,
.011064,-.010571,
.011464,-.01,
.011759,-.009368,
.011939,-.008695,
.012,-.008,
0.0*
%
%ADD23MACRO23*%
%AMMACRO21*
4,1,40,-.008,-.012,
.008,-.012,
.008695,-.011939,
.009368,-.011759,
.01,-.011464,
.010571,-.011064,
.011064,-.010571,
.011464,-.01,
.011759,-.009368,
.011939,-.008695,
.012,-.008,
.012,.008,
.011939,.008695,
.011759,.009368,
.011464,.01,
.011064,.010571,
.010571,.011064,
.01,.011464,
.009368,.011759,
.008695,.011939,
.008,.012,
-.008,.012,
-.008695,.011939,
-.009368,.011759,
-.01,.011464,
-.010571,.011064,
-.011064,.010571,
-.011464,.01,
-.011759,.009368,
-.011939,.008695,
-.012,.008,
-.012,-.008,
-.011939,-.008695,
-.011759,-.009368,
-.011464,-.01,
-.011064,-.010571,
-.010571,-.011064,
-.01,-.011464,
-.009368,-.011759,
-.008695,-.011939,
-.008,-.012,
0.0*
%
%ADD21MACRO21*%
%AMMACRO46*
4,1,40,-.011,.007,
-.011,-.007,
-.010939,-.007695,
-.010759,-.008368,
-.010464,-.009,
-.010064,-.009571,
-.009571,-.010064,
-.009,-.010464,
-.008368,-.010759,
-.007695,-.010939,
-.007,-.011,
.007,-.011,
.007695,-.010939,
.008368,-.010759,
.009,-.010464,
.009571,-.010064,
.010064,-.009571,
.010464,-.009,
.010759,-.008368,
.010939,-.007695,
.011,-.007,
.011,.007,
.010939,.007695,
.010759,.008368,
.010464,.009,
.010064,.009571,
.009571,.010064,
.009,.010464,
.008368,.010759,
.007695,.010939,
.007,.011,
-.007,.011,
-.007695,.010939,
-.008368,.010759,
-.009,.010464,
-.009571,.010064,
-.010064,.009571,
-.010464,.009,
-.010759,.008368,
-.010939,.007695,
-.011,.007,
0.0*
%
%ADD46MACRO46*%
%AMMACRO89*
4,1,6,.025,.0135,
.005,-.0065,
.005,-.0135,
-.005,-.0135,
-.005,-.0065,
-.025,.0135,
.025,.0135,
0.0*
%
%ADD89MACRO89*%
%AMMACRO64*
4,1,40,.013,.017,
-.013,.017,
-.013695,.016939,
-.014368,.016759,
-.015,.016464,
-.015571,.016064,
-.016064,.015571,
-.016464,.015,
-.016759,.014368,
-.016939,.013695,
-.017,.013,
-.017,-.013,
-.016939,-.013695,
-.016759,-.014368,
-.016464,-.015,
-.016064,-.015571,
-.015571,-.016064,
-.015,-.016464,
-.014368,-.016759,
-.013695,-.016939,
-.013,-.017,
.013,-.017,
.013695,-.016939,
.014368,-.016759,
.015,-.016464,
.015571,-.016064,
.016064,-.015571,
.016464,-.015,
.016759,-.014368,
.016939,-.013695,
.017,-.013,
.017,.013,
.016939,.013695,
.016759,.014368,
.016464,.015,
.016064,.015571,
.015571,.016064,
.015,.016464,
.014368,.016759,
.013695,.016939,
.013,.017,
0.0*
%
%ADD64MACRO64*%
%AMMACRO40*
4,1,40,.017,-.013,
.017,.013,
.016939,.013695,
.016759,.014368,
.016464,.015,
.016064,.015571,
.015571,.016064,
.015,.016464,
.014368,.016759,
.013695,.016939,
.013,.017,
-.013,.017,
-.013695,.016939,
-.014368,.016759,
-.015,.016464,
-.015571,.016064,
-.016064,.015571,
-.016464,.015,
-.016759,.014368,
-.016939,.013695,
-.017,.013,
-.017,-.013,
-.016939,-.013695,
-.016759,-.014368,
-.016464,-.015,
-.016064,-.015571,
-.015571,-.016064,
-.015,-.016464,
-.014368,-.016759,
-.013695,-.016939,
-.013,-.017,
.013,-.017,
.013695,-.016939,
.014368,-.016759,
.015,-.016464,
.015571,-.016064,
.016064,-.015571,
.016464,-.015,
.016759,-.014368,
.016939,-.013695,
.017,-.013,
0.0*
%
%ADD40MACRO40*%
%AMMACRO33*
4,1,40,-.007,-.011,
.007,-.011,
.007695,-.010939,
.008368,-.010759,
.009,-.010464,
.009571,-.010064,
.010064,-.009571,
.010464,-.009,
.010759,-.008368,
.010939,-.007695,
.011,-.007,
.011,.007,
.010939,.007695,
.010759,.008368,
.010464,.009,
.010064,.009571,
.009571,.010064,
.009,.010464,
.008368,.010759,
.007695,.010939,
.007,.011,
-.007,.011,
-.007695,.010939,
-.008368,.010759,
-.009,.010464,
-.009571,.010064,
-.010064,.009571,
-.010464,.009,
-.010759,.008368,
-.010939,.007695,
-.011,.007,
-.011,-.007,
-.010939,-.007695,
-.010759,-.008368,
-.010464,-.009,
-.010064,-.009571,
-.009571,-.010064,
-.009,-.010464,
-.008368,-.010759,
-.007695,-.010939,
-.007,-.011,
0.0*
%
%ADD33MACRO33*%
%AMMACRO22*
4,1,40,.012,-.008,
.012,.008,
.011939,.008695,
.011759,.009368,
.011464,.01,
.011064,.010571,
.010571,.011064,
.01,.011464,
.009368,.011759,
.008695,.011939,
.008,.012,
-.008,.012,
-.008695,.011939,
-.009368,.011759,
-.01,.011464,
-.010571,.011064,
-.011064,.010571,
-.011464,.01,
-.011759,.009368,
-.011939,.008695,
-.012,.008,
-.012,-.008,
-.011939,-.008695,
-.011759,-.009368,
-.011464,-.01,
-.011064,-.010571,
-.010571,-.011064,
-.01,-.011464,
-.009368,-.011759,
-.008695,-.011939,
-.008,-.012,
.008,-.012,
.008695,-.011939,
.009368,-.011759,
.01,-.011464,
.010571,-.011064,
.011064,-.010571,
.011464,-.01,
.011759,-.009368,
.011939,-.008695,
.012,-.008,
0.0*
%
%ADD22MACRO22*%
%AMMACRO20*
4,1,40,-.008,-.012,
.008,-.012,
.008695,-.011939,
.009368,-.011759,
.01,-.011464,
.010571,-.011064,
.011064,-.010571,
.011464,-.01,
.011759,-.009368,
.011939,-.008695,
.012,-.008,
.012,.008,
.011939,.008695,
.011759,.009368,
.011464,.01,
.011064,.010571,
.010571,.011064,
.01,.011464,
.009368,.011759,
.008695,.011939,
.008,.012,
-.008,.012,
-.008695,.011939,
-.009368,.011759,
-.01,.011464,
-.010571,.011064,
-.011064,.010571,
-.011464,.01,
-.011759,.009368,
-.011939,.008695,
-.012,.008,
-.012,-.008,
-.011939,-.008695,
-.011759,-.009368,
-.011464,-.01,
-.011064,-.010571,
-.010571,-.011064,
-.01,-.011464,
-.009368,-.011759,
-.008695,-.011939,
-.008,-.012,
0.0*
%
%ADD20MACRO20*%
%AMMACRO47*
4,1,40,-.011,.007,
-.011,-.007,
-.010939,-.007695,
-.010759,-.008368,
-.010464,-.009,
-.010064,-.009571,
-.009571,-.010064,
-.009,-.010464,
-.008368,-.010759,
-.007695,-.010939,
-.007,-.011,
.007,-.011,
.007695,-.010939,
.008368,-.010759,
.009,-.010464,
.009571,-.010064,
.010064,-.009571,
.010464,-.009,
.010759,-.008368,
.010939,-.007695,
.011,-.007,
.011,.007,
.010939,.007695,
.010759,.008368,
.010464,.009,
.010064,.009571,
.009571,.010064,
.009,.010464,
.008368,.010759,
.007695,.010939,
.007,.011,
-.007,.011,
-.007695,.010939,
-.008368,.010759,
-.009,.010464,
-.009571,.010064,
-.010064,.009571,
-.010464,.009,
-.010759,.008368,
-.010939,.007695,
-.011,.007,
0.0*
%
%ADD47MACRO47*%
%ADD93C,.006*%
G75*
%LPD*%
G75*
G36*
G01X19685Y279134D02*
Y281470D01*
G02X47245I13780J38D01*
G01Y279134D01*
X41340D01*
Y281479D01*
G03X25590I-7875J31D01*
G01Y279134D01*
X19685D01*
G37*
G36*
G01X7874Y1920473D02*
Y1922809D01*
G02X35434I13780J38D01*
G01Y1920473D01*
X29529D01*
Y1922818D01*
G03X13779I-7875J31D01*
G01Y1920473D01*
X7874D01*
G37*
G36*
G01X120078Y15355D02*
Y17691D01*
G02X147638I13780J38D01*
G01Y15355D01*
X141733D01*
Y17700D01*
G03X125983I-7875J31D01*
G01Y15355D01*
X120078D01*
G37*
G36*
G01X261811Y277166D02*
Y279502D01*
G02X289371I13780J38D01*
G01Y277166D01*
X283466D01*
Y279511D01*
G03X267716I-7875J31D01*
G01Y277166D01*
X261811D01*
G37*
G36*
G01Y682668D02*
Y685004D01*
G02X289371I13780J38D01*
G01Y682668D01*
X283466D01*
Y685013D01*
G03X267716I-7875J31D01*
G01Y682668D01*
X261811D01*
G37*
G36*
G01Y1086211D02*
Y1088547D01*
G02X289371I13780J38D01*
G01Y1086211D01*
X283466D01*
Y1088556D01*
G03X267716I-7875J31D01*
G01Y1086211D01*
X261811D01*
G37*
G36*
G01Y1901172D02*
Y1903508D01*
G02X289371I13780J38D01*
G01Y1901172D01*
X283466D01*
Y1903517D01*
G03X267716I-7875J31D01*
G01Y1901172D01*
X261811D01*
G37*
G36*
G01X984251Y161014D02*
Y163350D01*
G02X1011811I13780J38D01*
G01Y161014D01*
X1005906D01*
Y163359D01*
G03X990156I-7875J31D01*
G01Y161014D01*
X984251D01*
G37*
G36*
G01Y684636D02*
Y686972D01*
G02X1011811I13780J38D01*
G01Y684636D01*
X1005906D01*
Y686981D01*
G03X990156I-7875J31D01*
G01Y684636D01*
X984251D01*
G37*
G36*
G01Y1080305D02*
Y1082641D01*
G02X1011811I13780J38D01*
G01Y1080305D01*
X1005906D01*
Y1082650D01*
G03X990156I-7875J31D01*
G01Y1080305D01*
X984251D01*
G37*
G36*
G01X1021245Y1473722D02*
X995645D01*
Y1491397D01*
X1021245D01*
Y1473722D01*
G37*
G36*
G01X995645Y1493247D02*
X1021245D01*
Y1510922D01*
X995645D01*
Y1493247D01*
G37*
G36*
G01Y1453247D02*
X1021245D01*
Y1470922D01*
X995645D01*
Y1453247D01*
G37*
G36*
G01X1021245Y1433722D02*
X995645D01*
Y1451397D01*
X1021245D01*
Y1433722D01*
G37*
G36*
G01Y1553722D02*
X995645D01*
Y1571397D01*
X1021245D01*
Y1553722D01*
G37*
G36*
G01X995645Y1573247D02*
X1021245D01*
Y1590922D01*
X995645D01*
Y1573247D01*
G37*
G36*
G01X1021245Y1513722D02*
X995645D01*
Y1531397D01*
X1021245D01*
Y1513722D01*
G37*
G36*
G01X995645Y1533247D02*
X1021245D01*
Y1550922D01*
X995645D01*
Y1533247D01*
G37*
G36*
G01X1021244Y1593722D02*
Y1610922D01*
X995645D01*
Y1593722D01*
X1021244D01*
G37*
G36*
G01X984251Y1901172D02*
Y1903508D01*
G02X1011811I13780J38D01*
G01Y1901172D01*
X1005906D01*
Y1903517D01*
G03X990156I-7875J31D01*
G01Y1901172D01*
X984251D01*
G37*
G54D10*
X-63741Y15000D03*
X-42339Y1008909D03*
X-63741Y1977126D03*
X25499Y1950499D03*
X1010999Y43999D03*
X1010499Y1950499D03*
X1101142Y15000D03*
Y1977126D03*
G54D20*
X30200Y1488300D03*
X26600D03*
X32850Y1510400D03*
X36350D03*
X82000Y243688D03*
X98400Y435600D03*
X82000Y649200D03*
X98400Y841100D03*
X83248Y1052836D03*
X98400Y1246600D03*
X82748Y1458348D03*
X98900Y1652500D03*
X54872Y1674748D03*
X58372D03*
X115700Y40000D03*
X144400Y430800D03*
Y836300D03*
X144700Y1241800D03*
X145900Y1647300D03*
X193000Y56700D03*
X194606Y1769390D03*
X395600Y398100D03*
X393500Y380200D03*
X341000Y402700D03*
X344500D03*
X368500Y429200D03*
X372000D03*
X341000Y832700D03*
X344500D03*
X393500Y829700D03*
X368500Y858200D03*
X372000D03*
X393500Y1177700D03*
X341000Y1204200D03*
X344500D03*
X395600Y1198700D03*
X368500Y1229700D03*
X372000D03*
X395700Y1697200D03*
X341000Y1702700D03*
X344500D03*
X369000Y1727700D03*
X372500D03*
X417500Y809200D03*
Y817200D03*
Y1211700D03*
Y1219700D03*
Y1710200D03*
Y1718200D03*
G54D11*
X-49168Y52138D03*
X26000Y1965500D03*
X329500Y363500D03*
X327500Y1662000D03*
X404000Y432000D03*
X340500Y793500D03*
X405000Y862500D03*
X343000Y1166000D03*
X399500Y1734000D03*
X413500Y1247500D03*
X1009500Y27500D03*
X1010500Y1966000D03*
X1085741Y22661D03*
Y1967598D03*
G36*
G01X39370Y278851D02*
Y281496D01*
G03X27559I-5905J0D01*
G01Y278851D01*
G02X25809Y273902I-7873J0D01*
G03X41120I7656J-6187D01*
G02X39370Y278851I6123J4949D01*
G37*
G36*
G01X27559Y1920190D02*
Y1922835D01*
G03X15748I-5906J0D01*
G01Y1920190D01*
G02X13998Y1915241I-7873J0D01*
G03X29309I7656J-6187D01*
G02X27559Y1920190I6123J4949D01*
G37*
G36*
G01X139763Y15072D02*
Y17717D01*
G03X127952I-5906J0D01*
G01Y15072D01*
G02X126202Y10123I-7873J0D01*
G03X141513I7655J-6187D01*
G02X139763Y15072I6123J4949D01*
G37*
G36*
G01X281496Y276883D02*
Y279528D01*
G03X269685I-5905J0D01*
G01Y276883D01*
G02X267935Y271934I-7873J0D01*
G03X283246I7656J-6187D01*
G02X281496Y276883I6123J4949D01*
G37*
G36*
G01Y682385D02*
Y685030D01*
G03X269685I-5905J0D01*
G01Y682385D01*
G02X267935Y677436I-7873J0D01*
G03X283246I7656J-6187D01*
G02X281496Y682385I6123J4949D01*
G37*
G36*
G01Y1085928D02*
Y1088573D01*
G03X269685I-5905J0D01*
G01Y1085928D01*
G02X267935Y1080979I-7873J0D01*
G03X283246I7656J-6187D01*
G02X281496Y1085928I6123J4949D01*
G37*
G36*
G01Y1900889D02*
Y1903534D01*
G03X269685I-5905J0D01*
G01Y1900889D01*
G02X267935Y1895940I-7873J0D01*
G03X283246I7656J-6187D01*
G02X281496Y1900889I6123J4949D01*
G37*
G36*
G01X1003936Y160731D02*
Y163376D01*
G03X992125I-5905J0D01*
G01Y160731D01*
G02X990375Y155782I-7873J0D01*
G03X1005686I7656J-6187D01*
G02X1003936Y160731I6123J4949D01*
G37*
G36*
G01Y684353D02*
Y686998D01*
G03X992125I-5905J0D01*
G01Y684353D01*
G02X990375Y679404I-7873J0D01*
G03X1005686I7656J-6187D01*
G02X1003936Y684353I6123J4949D01*
G37*
G36*
G01Y1080022D02*
Y1082667D01*
G03X992125I-5905J0D01*
G01Y1080022D01*
G02X990375Y1075073I-7873J0D01*
G03X1005686I7656J-6187D01*
G02X1003936Y1080022I6123J4949D01*
G37*
G36*
G01Y1900889D02*
Y1903534D01*
G03X992125I-5905J0D01*
G01Y1900889D01*
G02X990375Y1895940I-7873J0D01*
G03X1005686I7656J-6187D01*
G02X1003936Y1900889I6123J4949D01*
G37*
G54D21*
X30200Y1491900D03*
X26600D03*
X32850Y1514000D03*
X36350D03*
X82000Y247288D03*
X98400Y439200D03*
X82000Y652800D03*
X98400Y844700D03*
X83248Y1056436D03*
X98400Y1250200D03*
X82748Y1461948D03*
X98900Y1656100D03*
X54872Y1678348D03*
X58372D03*
X115700Y43600D03*
X144400Y434400D03*
Y839900D03*
X144700Y1245400D03*
X145900Y1650900D03*
X193000Y60300D03*
X194606Y1772990D03*
X395600Y401700D03*
X393500Y383800D03*
X341000Y406300D03*
X344500D03*
X368500Y432800D03*
X372000D03*
X341000Y836300D03*
X344500D03*
X393500Y833300D03*
X368500Y861800D03*
X372000D03*
X393500Y1181300D03*
X341000Y1207800D03*
X344500D03*
X395600Y1202300D03*
X368500Y1233300D03*
X372000D03*
X395700Y1700800D03*
X341000Y1706300D03*
X344500D03*
X369000Y1731300D03*
X372500D03*
X417500Y812800D03*
Y820800D03*
Y1215300D03*
Y1223300D03*
Y1713800D03*
Y1721800D03*
G54D30*
X37300Y1964000D03*
X87589Y234415D03*
X76750Y234272D03*
X83589Y234415D03*
X63903Y212595D03*
X95700Y344700D03*
X90000Y372700D03*
X92500Y606700D03*
X63623Y614570D03*
X87589Y639927D03*
X76750Y639784D03*
X83589Y639927D03*
X95700Y750200D03*
X90000Y778200D03*
X45000Y1064200D03*
X41000D03*
X88000Y1046200D03*
X77750Y1044295D03*
X93000Y1012200D03*
X84000Y1046200D03*
X64040Y1023685D03*
X95700Y1156100D03*
X90000Y1183700D03*
X63797Y1429188D03*
X110000Y1476700D03*
X87589Y1450950D03*
X76750Y1450807D03*
X83589Y1450950D03*
X95000Y1552200D03*
X79375Y1583575D03*
X75256Y1587075D03*
X103025Y1584725D03*
X65500Y1936200D03*
X48000Y1884200D03*
X52000D03*
X61050Y1965250D03*
X114300Y69200D03*
X119300D03*
X121600Y51300D03*
X170402Y151153D03*
X163994Y154736D03*
X126445Y335017D03*
X113650Y373850D03*
X149125Y405825D03*
X152900Y434300D03*
X125300Y444500D03*
X150000Y544700D03*
X154500D03*
X162144Y575235D03*
X122445Y740617D03*
X152900Y839800D03*
X113650Y779350D03*
X149500Y811700D03*
X126800Y849000D03*
X113650Y1184850D03*
X122400Y1146000D03*
X153200Y1245300D03*
X149500Y1217200D03*
X126000Y1255500D03*
X170402Y1366688D03*
X164066Y1371527D03*
X126000Y1476700D03*
X118000D03*
X149500Y1622700D03*
X154400Y1650800D03*
X126900Y1661200D03*
X126500Y1947200D03*
X200000Y32200D03*
X201500Y60200D03*
X199000Y538700D03*
Y531200D03*
Y546200D03*
X229500Y953177D03*
X305100Y404000D03*
X309300Y396500D03*
X290580Y565700D03*
X298450D03*
X317500D03*
X304500Y833500D03*
X308600Y826000D03*
X305200Y1204950D03*
X309300Y1197450D03*
X293100Y1390200D03*
X284900D03*
X319500Y1395700D03*
X315500D03*
X287000Y1399200D03*
X291000D03*
X307500Y1395700D03*
X276500Y1717700D03*
X272500D03*
X306200Y1703450D03*
X310300Y1695950D03*
X287500Y1791700D03*
X279500D03*
X271500D03*
X358000Y70700D03*
X348500Y75200D03*
X382200Y88100D03*
X382000Y104700D03*
X348500Y127200D03*
X352500D03*
X353000Y348700D03*
X388500D03*
X345000D03*
X380500D03*
X344500Y435700D03*
X340500D03*
X359500D03*
X355500D03*
X395000D03*
X391000D03*
X376000D03*
X380000D03*
X382000Y778700D03*
X374000D03*
X355500Y865700D03*
X340500D03*
X344500D03*
X359500D03*
X380000D03*
X395000D03*
X376000D03*
X391000D03*
X388500Y1150200D03*
X380500D03*
X355500Y1237200D03*
X380000D03*
X376000D03*
X395000D03*
X391000D03*
X344500D03*
X340500D03*
X359500D03*
X353000Y1648700D03*
X345000D03*
X344500Y1735700D03*
X340500D03*
X359500D03*
X355500D03*
X764739Y1963207D03*
X832500Y177700D03*
X824500D03*
X816500D03*
X824000Y344700D03*
X816500Y372700D03*
X824000Y750200D03*
X816500Y778200D03*
X824000Y1155700D03*
X816500Y1183700D03*
X824000Y1561200D03*
X816500Y1589200D03*
X825500Y1791700D03*
X815000D03*
X788839Y1935207D03*
X788389Y1964357D03*
X899648Y150653D03*
X856200Y334200D03*
X840150Y373850D03*
X898754Y556165D03*
X856100Y740200D03*
X840150Y779350D03*
X898648Y961677D03*
X889909Y977307D03*
X840150Y1184850D03*
X854500Y1145600D03*
X898748Y1367188D03*
X890213Y1379896D03*
X855500Y1551200D03*
X840150Y1590350D03*
X881500Y1699700D03*
X898800Y1772700D03*
X906500Y1730700D03*
X890500D03*
X841500Y1791700D03*
X959000Y1663700D03*
G54D22*
X33000Y1778850D03*
Y1775350D03*
X80187Y1854268D03*
X180800Y553500D03*
X128300Y1502000D03*
X360800Y120500D03*
Y117000D03*
X367300Y76500D03*
X390800Y447500D03*
X355300D03*
X382800D03*
X347300D03*
X390800Y877500D03*
X355300D03*
X382800D03*
X347300D03*
X390800Y1249000D03*
X355300D03*
X382800D03*
X347300D03*
X355300Y1747500D03*
X347300D03*
X834800Y203000D03*
Y1817000D03*
X889300Y1698000D03*
X915300Y1691000D03*
Y1699000D03*
G54D40*
X100000Y124800D03*
Y530800D03*
Y935800D03*
Y1340800D03*
Y1755300D03*
X131000Y56600D03*
X144000Y247300D03*
X146600Y363100D03*
X144000Y653800D03*
X146500Y767900D03*
X144000Y1059300D03*
X148500Y1174300D03*
X144000Y1463800D03*
X136700Y1579800D03*
X144000Y1869800D03*
X118500Y1967400D03*
X865500Y362800D03*
X872500Y653800D03*
X865000Y768700D03*
X872500Y1059300D03*
X874500Y1174800D03*
X872500Y1464800D03*
X866000Y1580300D03*
X910500Y1713300D03*
X855000Y1702300D03*
X878000Y1728800D03*
X871500Y1869800D03*
X846500Y1967300D03*
G54D31*
X37300Y1960600D03*
X87589Y231015D03*
X76750Y230872D03*
X83589Y231015D03*
X63903Y209195D03*
X95700Y341300D03*
X90000Y369300D03*
X92500Y603300D03*
X63623Y611170D03*
X87589Y636527D03*
X76750Y636384D03*
X83589Y636527D03*
X95700Y746800D03*
X90000Y774800D03*
X45000Y1060800D03*
X41000D03*
X88000Y1042800D03*
X77750Y1040895D03*
X93000Y1008800D03*
X84000Y1042800D03*
X64040Y1020285D03*
X95700Y1152700D03*
X90000Y1180300D03*
X63797Y1425788D03*
X110000Y1473300D03*
X87589Y1447550D03*
X76750Y1447407D03*
X83589Y1447550D03*
X95000Y1548800D03*
X79375Y1580175D03*
X75256Y1583675D03*
X103025Y1581325D03*
X65500Y1932800D03*
X48000Y1880800D03*
X52000D03*
X61050Y1961850D03*
X121600Y47900D03*
X114300Y65800D03*
X119300D03*
X170402Y147753D03*
X163994Y151336D03*
X126445Y331617D03*
X113650Y370450D03*
X149125Y402425D03*
X152900Y430900D03*
X125300Y441100D03*
X150000Y541300D03*
X154500D03*
X162144Y571835D03*
X122445Y737217D03*
X152900Y836400D03*
X113650Y775950D03*
X149500Y808300D03*
X126800Y845600D03*
X113650Y1181450D03*
X122400Y1142600D03*
X153200Y1241900D03*
X149500Y1213800D03*
X126000Y1252100D03*
X170402Y1363288D03*
X164066Y1368127D03*
X126000Y1473300D03*
X118000D03*
X154400Y1647400D03*
X149500Y1619300D03*
X126900Y1657800D03*
X126500Y1943800D03*
X200000Y28800D03*
X201500Y56800D03*
X199000Y535300D03*
Y527800D03*
Y542800D03*
X229500Y949777D03*
X305100Y400600D03*
X309300Y393100D03*
X290580Y562300D03*
X298450D03*
X317500D03*
X304500Y830100D03*
X308600Y822600D03*
X305200Y1201550D03*
X309300Y1194050D03*
X293100Y1386800D03*
X284900D03*
X319500Y1392300D03*
X315500D03*
X287000Y1395800D03*
X291000D03*
X307500Y1392300D03*
X276500Y1714300D03*
X272500D03*
X306200Y1700050D03*
X310300Y1692550D03*
X287500Y1788300D03*
X279500D03*
X271500D03*
X358000Y67300D03*
X348500Y71800D03*
X382200Y84700D03*
X382000Y101300D03*
X348500Y123800D03*
X352500D03*
X353000Y345300D03*
X388500D03*
X345000D03*
X380500D03*
X344500Y432300D03*
X340500D03*
X359500D03*
X355500D03*
X395000D03*
X391000D03*
X376000D03*
X380000D03*
X382000Y775300D03*
X374000D03*
X355500Y862300D03*
X340500D03*
X344500D03*
X359500D03*
X380000D03*
X395000D03*
X376000D03*
X391000D03*
X388500Y1146800D03*
X380500D03*
X355500Y1233800D03*
X380000D03*
X376000D03*
X395000D03*
X391000D03*
X344500D03*
X340500D03*
X359500D03*
X353000Y1645300D03*
X345000D03*
X344500Y1732300D03*
X340500D03*
X359500D03*
X355500D03*
X764739Y1959807D03*
X832500Y174300D03*
X824500D03*
X816500D03*
X824000Y341300D03*
X816500Y369300D03*
X824000Y746800D03*
X816500Y774800D03*
X824000Y1152300D03*
X816500Y1180300D03*
X824000Y1557800D03*
X816500Y1585800D03*
X825500Y1788300D03*
X815000D03*
X788839Y1931807D03*
X788389Y1960957D03*
X899648Y147253D03*
X856200Y330800D03*
X840150Y370450D03*
X898754Y552765D03*
X856100Y736800D03*
X840150Y775950D03*
X898648Y958277D03*
X889909Y973907D03*
X840150Y1181450D03*
X854500Y1142200D03*
X898748Y1363788D03*
X890213Y1376496D03*
X855500Y1547800D03*
X840150Y1586950D03*
X881500Y1696300D03*
X898800Y1769300D03*
X906500Y1727300D03*
X890500D03*
X841500Y1788300D03*
X959000Y1660300D03*
G54D13*
X23426Y281496D03*
X24764Y286496D03*
X28426Y290197D03*
X38465D03*
X42166Y286496D03*
X11615Y1922835D03*
X12953Y1927835D03*
X16615Y1931536D03*
X26654D03*
X30355Y1927835D03*
X31693Y1922835D03*
X43504Y281496D03*
X123819Y17717D03*
X125157Y22717D03*
X128819Y26418D03*
X138858D03*
X142559Y22717D03*
X143897Y17717D03*
X265552Y279528D03*
X266890Y284528D03*
X270552Y288229D03*
X280591D03*
X284292Y284528D03*
X285630Y279528D03*
X265552Y685030D03*
X266890Y690030D03*
X270552Y693731D03*
X280591D03*
X284292Y690030D03*
X285630Y685030D03*
X265552Y1088573D03*
X266890Y1093573D03*
X270552Y1097274D03*
X280591D03*
X284292Y1093573D03*
X285630Y1088573D03*
X265552Y1903534D03*
X266890Y1908534D03*
X270552Y1912235D03*
X280591D03*
X284292Y1908534D03*
X285630Y1903534D03*
X987992Y163376D03*
Y686998D03*
Y1082667D03*
Y1903534D03*
X989330Y168376D03*
X992992Y172077D03*
X1003031D03*
X1006732Y168376D03*
X1008070Y163376D03*
X989330Y691998D03*
X992992Y695699D03*
X1003031D03*
X1006732Y691998D03*
X1008070Y686998D03*
X989330Y1087667D03*
X992992Y1091368D03*
X1003031D03*
X1006732Y1087667D03*
X1008070Y1082667D03*
X989330Y1908534D03*
X992992Y1912235D03*
X1003031D03*
X1006732Y1908534D03*
X1008070Y1903534D03*
G54D23*
X29400Y1778850D03*
Y1775350D03*
X76587Y1854268D03*
X177200Y553500D03*
X124700Y1502000D03*
X357200Y120500D03*
Y117000D03*
X363700Y76500D03*
X387200Y447500D03*
X351700D03*
X379200D03*
X343700D03*
X387200Y877500D03*
X351700D03*
X379200D03*
X343700D03*
X387200Y1249000D03*
X351700D03*
X379200D03*
X343700D03*
X351700Y1747500D03*
X343700D03*
X831200Y203000D03*
Y1817000D03*
X911700Y1691000D03*
Y1699000D03*
X885700Y1698000D03*
G54D32*
X36775Y1970275D03*
X88875Y377775D03*
Y783275D03*
X66895Y1012436D03*
X88875Y1188775D03*
X67540Y1417910D03*
X96200Y1497000D03*
Y1492000D03*
X87800Y1840600D03*
X97800Y1839900D03*
X87800Y1836300D03*
X88300Y1867400D03*
X148100Y426600D03*
X119200Y454500D03*
Y449500D03*
X170700Y556330D03*
X170695Y560416D03*
X148100Y832100D03*
X119200Y860000D03*
Y855000D03*
X169617Y960000D03*
X168230Y979729D03*
X148400Y1237600D03*
X119200Y1265500D03*
Y1260500D03*
X154659Y1352302D03*
Y1347802D03*
X112500Y1543700D03*
X149600Y1643100D03*
X119200Y1671000D03*
Y1666000D03*
X122400Y1943900D03*
X196700Y52500D03*
X193700Y135000D03*
X203700Y569000D03*
X194854Y1346488D03*
X328200Y408500D03*
Y404400D03*
Y421000D03*
Y417000D03*
Y425000D03*
X329200Y609000D03*
Y597000D03*
X280200Y573000D03*
Y565000D03*
Y585000D03*
Y577000D03*
Y597000D03*
Y589000D03*
X329200D03*
X328200Y838500D03*
Y847000D03*
Y834400D03*
Y851000D03*
Y855000D03*
Y1210000D03*
Y1205800D03*
Y1222500D03*
Y1218500D03*
Y1226500D03*
X280200Y1419500D03*
Y1411500D03*
Y1423500D03*
Y1403500D03*
Y1431500D03*
X328200Y1721000D03*
Y1708500D03*
Y1717000D03*
Y1704300D03*
X272200Y1722000D03*
X328200Y1725000D03*
X367200Y58000D03*
X334200Y377000D03*
X338200Y389000D03*
X334200Y381000D03*
Y385000D03*
X390700Y459000D03*
X355200D03*
X382700D03*
X347200D03*
X334200Y807000D03*
X338200Y819000D03*
X334200Y815000D03*
Y811000D03*
X390700Y889000D03*
X355200D03*
X382700D03*
X347200D03*
X338200Y1190500D03*
X334200Y1178500D03*
Y1182500D03*
Y1186500D03*
X390700Y1260500D03*
X355200D03*
X382700D03*
X347200D03*
X334200Y1677000D03*
X338200Y1691000D03*
X334200Y1681000D03*
Y1685000D03*
X355200Y1759000D03*
X347200D03*
X405700Y820000D03*
Y805000D03*
Y824000D03*
Y809000D03*
Y1207500D03*
Y1211500D03*
Y1222500D03*
Y1226500D03*
Y1721000D03*
Y1706000D03*
Y1710000D03*
Y1725000D03*
X763614Y1968282D03*
X802700Y193000D03*
Y198000D03*
X815375Y377775D03*
Y783275D03*
Y1188775D03*
Y1594275D03*
X802700Y1812000D03*
Y1807000D03*
X889700Y157000D03*
Y161000D03*
X898675Y154724D03*
X890516Y168354D03*
X865200Y553465D03*
X887950Y556715D03*
Y560715D03*
X896941Y560408D03*
X865200Y958977D03*
X887950Y962227D03*
Y966227D03*
X897174Y965913D03*
X865200Y1364488D03*
X887388Y1365200D03*
Y1369700D03*
X896785Y1371351D03*
X887950Y1773250D03*
X865200Y1770000D03*
X887950Y1777250D03*
X897100Y1776900D03*
X851300Y1945200D03*
X923200Y129953D03*
Y535465D03*
Y940977D03*
Y1346488D03*
X954700Y1668500D03*
Y1663500D03*
X919200Y1715000D03*
X923200Y1752000D03*
G54D41*
X75710Y209868D03*
Y206668D03*
X69960Y209868D03*
Y206668D03*
X75710Y615380D03*
Y612180D03*
X69960Y615380D03*
Y612180D03*
X75710Y1020891D03*
Y1017691D03*
X69960Y1020891D03*
Y1017691D03*
X75710Y1426403D03*
Y1423203D03*
X69960Y1426403D03*
Y1423203D03*
X75710Y1831915D03*
Y1828715D03*
X69960Y1831915D03*
Y1828715D03*
X174135Y163411D03*
Y160211D03*
X168385Y163411D03*
Y160211D03*
X174135Y568923D03*
Y565723D03*
X168385Y568923D03*
Y565723D03*
X174135Y974435D03*
Y971235D03*
X168385Y974435D03*
Y971235D03*
X174135Y1379946D03*
Y1376746D03*
X168385Y1379946D03*
Y1376746D03*
X174135Y1785458D03*
Y1782258D03*
X168385Y1785458D03*
Y1782258D03*
X902481Y163411D03*
Y160211D03*
X896731Y163411D03*
Y160211D03*
X902481Y568923D03*
Y565723D03*
X896731Y568923D03*
Y565723D03*
X902481Y974435D03*
Y971235D03*
X896731Y974435D03*
Y971235D03*
X902481Y1379946D03*
Y1376746D03*
X896731Y1379946D03*
Y1376746D03*
X902481Y1785458D03*
Y1782258D03*
X896731Y1785458D03*
Y1782258D03*
G54D50*
X99700Y341200D03*
Y746700D03*
Y1152600D03*
X99000Y1548700D03*
X69500Y1932700D03*
X175894Y137863D03*
X145700Y336600D03*
X145800Y742300D03*
X182000Y952700D03*
X145800Y1146800D03*
X175894Y1352998D03*
X145800Y1550500D03*
X133200Y1950900D03*
X373500Y101200D03*
X374300Y84600D03*
X372000Y367700D03*
X368500D03*
X393500Y414700D03*
X343000Y416700D03*
X346500D03*
X362000Y800200D03*
X393500Y844700D03*
X365500Y800200D03*
X343000Y846700D03*
X346500D03*
X367500Y1171200D03*
X371000D03*
X393500Y1221700D03*
X343000Y1218200D03*
X346500D03*
X376000Y1670200D03*
X343000Y1716700D03*
X346500D03*
X372500Y1670200D03*
X828000Y341200D03*
Y746700D03*
Y1152200D03*
Y1557700D03*
X792839Y1931707D03*
X905240Y136463D03*
X874200Y336700D03*
X904240Y541975D03*
X874100Y743200D03*
X904240Y947487D03*
X874100Y1147700D03*
X904240Y1352998D03*
X874200Y1553900D03*
X841500Y1698700D03*
X904240Y1758510D03*
X862500Y1951500D03*
X994600Y1417500D03*
G54D14*
X11811Y571426D03*
Y949378D03*
Y1067489D03*
Y1484811D03*
Y1445441D03*
Y1862763D03*
G54D33*
X33375Y1970275D03*
X85475Y377775D03*
Y783275D03*
X63495Y1012436D03*
X85475Y1188775D03*
X64140Y1417910D03*
X92800Y1497000D03*
Y1492000D03*
X109100Y1543700D03*
X84400Y1840600D03*
X94400Y1839900D03*
X84400Y1836300D03*
X84900Y1867400D03*
X144700Y426600D03*
X115800Y454500D03*
Y449500D03*
X167300Y556330D03*
X167295Y560416D03*
X144700Y832100D03*
X115800Y860000D03*
Y855000D03*
X166217Y960000D03*
X164830Y979729D03*
X145000Y1237600D03*
X115800Y1265500D03*
Y1260500D03*
X151259Y1352302D03*
Y1347802D03*
X146200Y1643100D03*
X115800Y1671000D03*
Y1666000D03*
X119000Y1943900D03*
X193300Y52500D03*
X190300Y135000D03*
X200300Y569000D03*
X191454Y1346488D03*
X324800Y408500D03*
Y404400D03*
Y421000D03*
Y417000D03*
Y425000D03*
X325800Y609000D03*
Y597000D03*
X276800Y573000D03*
Y565000D03*
Y585000D03*
Y577000D03*
Y597000D03*
Y589000D03*
X325800D03*
X324800Y838500D03*
Y847000D03*
Y834400D03*
Y851000D03*
Y855000D03*
Y1210000D03*
Y1205800D03*
Y1222500D03*
Y1218500D03*
Y1226500D03*
X276800Y1419500D03*
Y1411500D03*
Y1423500D03*
Y1403500D03*
Y1431500D03*
X324800Y1721000D03*
Y1708500D03*
Y1717000D03*
Y1704300D03*
X268800Y1722000D03*
X324800Y1725000D03*
X363800Y58000D03*
X330800Y377000D03*
X334800Y389000D03*
X330800Y381000D03*
Y385000D03*
X387300Y459000D03*
X351800D03*
X379300D03*
X343800D03*
X330800Y807000D03*
X402300Y820000D03*
Y805000D03*
Y824000D03*
Y809000D03*
X334800Y819000D03*
X330800Y815000D03*
Y811000D03*
X387300Y889000D03*
X351800D03*
X379300D03*
X343800D03*
X334800Y1190500D03*
X402300Y1207500D03*
Y1211500D03*
X330800Y1178500D03*
Y1182500D03*
Y1186500D03*
X387300Y1260500D03*
X351800D03*
X402300Y1222500D03*
Y1226500D03*
X379300Y1260500D03*
X343800D03*
X330800Y1677000D03*
X334800Y1691000D03*
X402300Y1721000D03*
Y1706000D03*
Y1710000D03*
X330800Y1681000D03*
Y1685000D03*
X351800Y1759000D03*
X402300Y1725000D03*
X343800Y1759000D03*
X760214Y1968282D03*
X799300Y193000D03*
Y198000D03*
X811975Y377775D03*
Y783275D03*
Y1188775D03*
Y1594275D03*
X799300Y1812000D03*
Y1807000D03*
X886300Y157000D03*
Y161000D03*
X895275Y154724D03*
X887116Y168354D03*
X861800Y553465D03*
X884550Y556715D03*
Y560715D03*
X893541Y560408D03*
X861800Y958977D03*
X884550Y962227D03*
Y966227D03*
X893774Y965913D03*
X861800Y1364488D03*
X883988Y1365200D03*
Y1369700D03*
X893385Y1371351D03*
X884550Y1773250D03*
X861800Y1770000D03*
X884550Y1777250D03*
X893700Y1776900D03*
X847900Y1945200D03*
X919800Y129953D03*
Y535465D03*
Y940977D03*
Y1346488D03*
X951300Y1668500D03*
Y1663500D03*
X915800Y1715000D03*
X919800Y1752000D03*
G54D15*
X8858Y629693D03*
Y626544D03*
Y623394D03*
Y620245D03*
Y617095D03*
Y613945D03*
Y610796D03*
Y607646D03*
Y604496D03*
Y601347D03*
Y598197D03*
Y702134D03*
Y698985D03*
Y695835D03*
Y692685D03*
Y689536D03*
Y686386D03*
Y683237D03*
Y680087D03*
Y676937D03*
Y673788D03*
Y670638D03*
Y667489D03*
Y664339D03*
Y661189D03*
Y658040D03*
Y654890D03*
Y651741D03*
Y648591D03*
Y645441D03*
Y642292D03*
Y639142D03*
Y635993D03*
Y632843D03*
Y774575D03*
Y771426D03*
Y768276D03*
Y765126D03*
Y761977D03*
Y758827D03*
Y755678D03*
Y752528D03*
Y749378D03*
Y733630D03*
Y730481D03*
Y727331D03*
Y724182D03*
Y721032D03*
Y717882D03*
Y714733D03*
Y711583D03*
Y708433D03*
Y705284D03*
Y847016D03*
Y843867D03*
Y840717D03*
Y837567D03*
Y834418D03*
Y831268D03*
Y828119D03*
Y824969D03*
Y821819D03*
Y818670D03*
Y815520D03*
Y812371D03*
Y809221D03*
Y806071D03*
Y802922D03*
Y799772D03*
Y796622D03*
Y793473D03*
Y790323D03*
Y787174D03*
Y784024D03*
Y780874D03*
Y777725D03*
Y919457D03*
Y916308D03*
Y913158D03*
Y910008D03*
Y906859D03*
Y903709D03*
Y900559D03*
Y897410D03*
Y894260D03*
Y891111D03*
Y887961D03*
Y884811D03*
Y881662D03*
Y878512D03*
Y875363D03*
Y872213D03*
Y869063D03*
Y865914D03*
Y862764D03*
Y859615D03*
Y856465D03*
Y853315D03*
Y850166D03*
Y922607D03*
Y1138355D03*
Y1135205D03*
Y1132056D03*
Y1128906D03*
Y1125756D03*
Y1122607D03*
Y1119457D03*
Y1116308D03*
Y1113158D03*
Y1110008D03*
Y1106859D03*
Y1103709D03*
Y1100559D03*
Y1097410D03*
Y1094260D03*
Y1210796D03*
Y1207646D03*
Y1204496D03*
Y1201347D03*
Y1198197D03*
Y1195048D03*
Y1191898D03*
Y1188748D03*
Y1185599D03*
Y1182449D03*
Y1179300D03*
Y1176150D03*
Y1173000D03*
Y1169851D03*
Y1166701D03*
Y1163552D03*
Y1160402D03*
Y1157252D03*
Y1154103D03*
Y1150953D03*
Y1147804D03*
Y1144654D03*
Y1141504D03*
Y1283237D03*
Y1280087D03*
Y1276937D03*
Y1273788D03*
Y1270638D03*
Y1267489D03*
Y1264339D03*
Y1261189D03*
Y1258040D03*
Y1254890D03*
Y1251741D03*
Y1248591D03*
Y1245441D03*
Y1229693D03*
Y1226544D03*
Y1223394D03*
Y1220245D03*
Y1217095D03*
Y1213945D03*
Y1355678D03*
Y1352528D03*
Y1349378D03*
Y1346229D03*
Y1343079D03*
Y1339930D03*
Y1336780D03*
Y1333630D03*
Y1330481D03*
Y1327331D03*
Y1324182D03*
Y1321032D03*
Y1317882D03*
Y1314733D03*
Y1311583D03*
Y1308434D03*
Y1305284D03*
Y1302134D03*
Y1298985D03*
Y1295835D03*
Y1292685D03*
Y1289536D03*
Y1286386D03*
Y1418670D03*
Y1415520D03*
Y1412371D03*
Y1409221D03*
Y1406071D03*
Y1402922D03*
Y1399772D03*
Y1396622D03*
Y1393473D03*
Y1390323D03*
Y1387174D03*
Y1384024D03*
Y1380874D03*
Y1377725D03*
Y1374575D03*
Y1371426D03*
Y1368276D03*
Y1365126D03*
Y1361977D03*
Y1358827D03*
Y1574574D03*
Y1571425D03*
Y1568275D03*
Y1565126D03*
Y1561976D03*
Y1558826D03*
Y1555677D03*
Y1552527D03*
Y1549378D03*
Y1546228D03*
Y1543078D03*
Y1539929D03*
Y1536779D03*
Y1533630D03*
Y1530480D03*
Y1527330D03*
Y1524181D03*
Y1521031D03*
Y1517881D03*
Y1514732D03*
Y1511582D03*
Y1647015D03*
Y1643866D03*
Y1640716D03*
Y1637567D03*
Y1634417D03*
Y1631267D03*
Y1628118D03*
Y1624968D03*
Y1621818D03*
Y1618669D03*
Y1615519D03*
Y1612370D03*
Y1609220D03*
Y1606070D03*
Y1602921D03*
Y1599771D03*
Y1596622D03*
Y1593472D03*
Y1590322D03*
Y1587173D03*
Y1584023D03*
Y1580874D03*
Y1577724D03*
Y1719456D03*
Y1716307D03*
Y1713157D03*
Y1710007D03*
Y1706858D03*
Y1703708D03*
Y1700559D03*
Y1697409D03*
Y1694259D03*
Y1691110D03*
Y1687960D03*
Y1684811D03*
Y1681661D03*
Y1678511D03*
Y1675362D03*
Y1672212D03*
Y1669063D03*
Y1665913D03*
Y1662763D03*
Y1791897D03*
Y1788748D03*
Y1785598D03*
Y1782448D03*
Y1779299D03*
Y1776149D03*
Y1773000D03*
Y1769850D03*
Y1766700D03*
Y1763551D03*
Y1760401D03*
Y1757252D03*
Y1754102D03*
Y1750952D03*
Y1747803D03*
Y1744653D03*
Y1741504D03*
Y1738354D03*
Y1735204D03*
Y1732055D03*
Y1728905D03*
Y1725756D03*
Y1722606D03*
Y1835992D03*
Y1832842D03*
Y1829693D03*
Y1826543D03*
Y1823393D03*
Y1820244D03*
Y1817094D03*
Y1813944D03*
Y1810795D03*
Y1807645D03*
Y1804496D03*
Y1801346D03*
Y1798196D03*
Y1795047D03*
G54D24*
X32600Y1823200D03*
Y1819700D03*
X151700Y569500D03*
X344700Y352500D03*
X380200D03*
X352700D03*
X388200D03*
X373700Y782500D03*
X381700D03*
X388200Y806500D03*
X380200Y1154000D03*
X388200D03*
X344700Y1652500D03*
X352700D03*
X385200Y1676500D03*
X386200Y1723500D03*
X914700Y1719000D03*
G54D51*
X108400Y412000D03*
X108700Y817500D03*
X97600Y1223600D03*
X108600Y1628200D03*
X297600Y1395700D03*
X288000Y1746200D03*
X293000D03*
X872500Y245200D03*
X896500Y1685200D03*
X877000Y1695200D03*
X901500Y1685200D03*
X959000Y1621600D03*
X990500Y1416700D03*
G54D42*
X73208Y220484D03*
X80708Y216609D03*
Y224359D03*
X94250Y223965D03*
X101750Y220090D03*
Y227840D03*
X94250Y629477D03*
X101750Y625602D03*
X73208Y625996D03*
X80708Y622121D03*
Y629871D03*
X101750Y633352D03*
X94250Y1034988D03*
X101750Y1031113D03*
Y1038863D03*
X73208Y1031507D03*
X80708Y1027632D03*
Y1035382D03*
X94250Y1440500D03*
X101750Y1436625D03*
Y1444375D03*
X73208Y1437019D03*
X80708Y1433144D03*
Y1440894D03*
X167250Y27600D03*
X174750Y23725D03*
Y31475D03*
X116375Y401225D03*
X123875Y397350D03*
Y405100D03*
X135875Y401225D03*
X143375Y397350D03*
Y405100D03*
X116750Y807100D03*
X124250Y803225D03*
Y810975D03*
X136250Y807100D03*
X143750Y803225D03*
Y810975D03*
X116750Y1212600D03*
X124250Y1208725D03*
X136250Y1212600D03*
X143750Y1208725D03*
X124250Y1216475D03*
X143750D03*
X136250Y1618100D03*
X143750Y1614225D03*
Y1621975D03*
X116750Y1618100D03*
X124250Y1614225D03*
Y1621975D03*
X180596Y1763500D03*
X186750Y27600D03*
X194250Y23725D03*
Y31475D03*
X209750Y555125D03*
X202250Y559000D03*
X209750Y562875D03*
X188096Y1759625D03*
Y1767375D03*
G54D60*
X104000Y1482000D03*
X154500Y536000D03*
X358000Y76000D03*
X810500Y183000D03*
Y1797000D03*
G54D52*
X95700Y355250D03*
X99575Y362750D03*
X91825D03*
X95700Y760750D03*
X99575Y768250D03*
X91825D03*
X95700Y1166650D03*
X99575Y1174150D03*
X91825D03*
X95000Y1562750D03*
X98875Y1570250D03*
X91125D03*
X67600Y1844650D03*
X71475Y1852150D03*
X63725D03*
X65500Y1946750D03*
X69375Y1954250D03*
X61625D03*
X151000Y148750D03*
X154875Y156250D03*
X147125D03*
X140000Y556250D03*
X143875Y563750D03*
X136125D03*
X155000Y1364285D03*
X158875Y1371785D03*
X151125D03*
X191500Y140750D03*
X195375Y148250D03*
X187625D03*
X205000Y945227D03*
X208875Y952727D03*
X201125D03*
X219500Y945227D03*
X223375Y952727D03*
X215625D03*
X192154Y1353738D03*
X196029Y1361238D03*
X188279D03*
X221000Y1756250D03*
X224875Y1763750D03*
X217125D03*
X235500Y1756250D03*
X239375Y1763750D03*
X231625D03*
X824000Y355250D03*
X820125Y362750D03*
X827875D03*
X824000Y760750D03*
X820125Y768250D03*
X827875D03*
X824000Y1166250D03*
X820125Y1173750D03*
X827875D03*
X824000Y1571750D03*
X820125Y1579250D03*
X827875D03*
X788839Y1945757D03*
X784964Y1953257D03*
X792714D03*
X920500Y137203D03*
X916625Y144703D03*
X924375D03*
X920500Y542715D03*
X916625Y550215D03*
X924375D03*
X920500Y948227D03*
X916625Y955727D03*
X924375D03*
X920500Y1353738D03*
X916625Y1361238D03*
X924375D03*
X920500Y1759250D03*
X924375Y1766750D03*
X916625D03*
G54D34*
X89764Y41771D03*
Y44921D03*
Y48070D03*
Y51220D03*
Y54370D03*
Y57519D03*
Y60669D03*
Y63818D03*
Y66968D03*
Y70118D03*
Y73267D03*
Y76417D03*
Y79567D03*
Y82716D03*
Y85866D03*
Y89015D03*
Y92165D03*
Y95315D03*
Y98464D03*
Y101614D03*
Y104763D03*
Y107913D03*
Y111063D03*
Y114212D03*
Y117362D03*
Y120511D03*
X77205Y115787D03*
Y118937D03*
X89764Y123661D03*
Y126811D03*
Y129960D03*
Y133110D03*
Y136259D03*
Y139409D03*
Y142559D03*
Y145708D03*
Y148858D03*
Y152007D03*
Y155157D03*
Y158307D03*
Y161456D03*
Y164606D03*
X77205Y122086D03*
Y125236D03*
Y128385D03*
Y131535D03*
X89764Y447283D03*
Y450433D03*
Y453582D03*
Y456732D03*
Y459882D03*
Y463031D03*
Y466181D03*
Y469330D03*
Y472480D03*
Y475630D03*
Y478779D03*
Y481929D03*
Y485079D03*
Y488228D03*
Y491378D03*
Y494527D03*
Y497677D03*
Y500827D03*
Y503976D03*
Y507126D03*
Y510275D03*
Y513425D03*
Y516575D03*
Y519724D03*
Y522874D03*
Y526023D03*
Y529173D03*
Y532323D03*
Y535472D03*
Y538622D03*
Y541771D03*
Y544921D03*
Y548071D03*
Y551220D03*
Y554370D03*
Y557519D03*
X77205Y521299D03*
Y524449D03*
Y527598D03*
Y530748D03*
Y533897D03*
Y537047D03*
X89764Y560669D03*
Y563819D03*
Y566968D03*
Y570118D03*
Y852795D03*
Y855945D03*
Y859094D03*
Y862244D03*
Y865394D03*
Y868543D03*
Y871693D03*
Y874842D03*
Y877992D03*
Y881142D03*
Y884291D03*
Y887441D03*
Y890591D03*
Y893740D03*
Y896890D03*
Y900039D03*
Y903189D03*
Y906339D03*
Y909488D03*
Y912638D03*
Y915787D03*
Y918937D03*
Y922087D03*
Y925236D03*
Y928386D03*
Y931535D03*
Y934685D03*
Y937835D03*
Y940984D03*
Y944134D03*
Y947283D03*
Y950433D03*
Y953583D03*
Y956732D03*
Y959882D03*
Y963031D03*
Y966181D03*
Y969331D03*
Y972480D03*
Y975630D03*
X77205Y926811D03*
Y929961D03*
Y933110D03*
Y936260D03*
Y939409D03*
Y942559D03*
X89764Y1258307D03*
Y1261457D03*
Y1264606D03*
Y1267756D03*
Y1270906D03*
Y1274055D03*
Y1277205D03*
Y1280354D03*
Y1283504D03*
Y1286654D03*
Y1289803D03*
Y1292953D03*
Y1296103D03*
Y1299252D03*
Y1302402D03*
Y1305551D03*
Y1308701D03*
Y1311851D03*
Y1315000D03*
Y1318150D03*
Y1321299D03*
Y1324449D03*
Y1327599D03*
Y1330748D03*
Y1333898D03*
Y1337047D03*
Y1340197D03*
Y1343347D03*
Y1346496D03*
Y1349646D03*
Y1352795D03*
Y1355945D03*
X77205Y1332323D03*
Y1335473D03*
Y1338622D03*
Y1341772D03*
Y1344921D03*
Y1348071D03*
X89764Y1359095D03*
Y1362244D03*
Y1365394D03*
Y1368543D03*
Y1371693D03*
Y1374843D03*
Y1377992D03*
Y1381142D03*
Y1663819D03*
Y1666969D03*
Y1670118D03*
Y1673268D03*
Y1676418D03*
Y1679567D03*
Y1682717D03*
Y1685866D03*
Y1689016D03*
Y1692166D03*
Y1695315D03*
Y1698465D03*
Y1701615D03*
Y1704764D03*
Y1707914D03*
Y1711063D03*
Y1714213D03*
Y1717363D03*
Y1720512D03*
Y1723662D03*
Y1726811D03*
Y1729961D03*
Y1733111D03*
Y1736260D03*
Y1739410D03*
Y1742559D03*
Y1745709D03*
Y1748859D03*
Y1752008D03*
Y1755158D03*
Y1758307D03*
Y1761457D03*
Y1764607D03*
Y1767756D03*
Y1770906D03*
Y1774055D03*
Y1777205D03*
Y1780355D03*
Y1783504D03*
Y1786654D03*
X77205Y1737835D03*
Y1740985D03*
Y1744134D03*
Y1747284D03*
Y1750433D03*
Y1753583D03*
X154331Y265315D03*
Y262165D03*
Y259015D03*
Y255866D03*
Y252716D03*
Y249567D03*
Y246417D03*
Y243267D03*
Y240118D03*
Y236968D03*
Y233819D03*
Y230669D03*
Y227519D03*
Y224370D03*
Y221220D03*
Y218071D03*
Y214921D03*
Y211771D03*
Y208622D03*
Y205472D03*
X166890Y254291D03*
Y251141D03*
Y247992D03*
Y244842D03*
Y241693D03*
Y238543D03*
X154331Y328307D03*
Y325157D03*
Y322008D03*
Y318858D03*
Y315708D03*
Y312559D03*
Y309409D03*
Y306260D03*
Y303110D03*
Y299960D03*
Y296811D03*
Y293661D03*
Y290511D03*
Y287362D03*
Y284212D03*
Y281063D03*
Y277913D03*
Y274763D03*
Y271614D03*
Y268464D03*
Y629882D03*
Y626732D03*
Y623583D03*
Y620433D03*
Y617283D03*
Y614134D03*
Y610984D03*
Y702323D03*
Y699173D03*
Y696023D03*
Y692874D03*
Y689724D03*
Y686575D03*
Y683425D03*
Y680275D03*
Y677126D03*
Y673976D03*
Y670827D03*
Y667677D03*
Y664527D03*
Y661378D03*
Y658228D03*
Y655079D03*
Y651929D03*
Y648779D03*
Y645630D03*
Y642480D03*
Y639331D03*
Y636181D03*
Y633031D03*
X166890Y659803D03*
Y656653D03*
Y653504D03*
Y650354D03*
Y647205D03*
Y644055D03*
X154331Y733819D03*
Y730669D03*
Y727520D03*
Y724370D03*
Y721220D03*
Y718071D03*
Y714921D03*
Y711772D03*
Y708622D03*
Y705472D03*
Y1063740D03*
Y1060591D03*
Y1057441D03*
Y1054291D03*
Y1051142D03*
Y1047992D03*
Y1044843D03*
Y1041693D03*
Y1038543D03*
Y1035394D03*
Y1032244D03*
Y1029095D03*
Y1025945D03*
Y1022795D03*
Y1019646D03*
Y1016496D03*
X166890Y1065315D03*
Y1062165D03*
Y1059016D03*
Y1055866D03*
Y1052717D03*
Y1049567D03*
X154331Y1139331D03*
Y1136181D03*
Y1133032D03*
Y1129882D03*
Y1126732D03*
Y1123583D03*
Y1120433D03*
Y1117284D03*
Y1114134D03*
Y1110984D03*
Y1107835D03*
Y1104685D03*
Y1101535D03*
Y1098386D03*
Y1095236D03*
Y1092087D03*
Y1088937D03*
Y1085787D03*
Y1082638D03*
Y1079488D03*
Y1076339D03*
Y1073189D03*
Y1070039D03*
Y1066890D03*
Y1428307D03*
Y1425158D03*
Y1422008D03*
Y1500748D03*
Y1497599D03*
Y1494449D03*
Y1491299D03*
Y1488150D03*
Y1485000D03*
Y1481851D03*
Y1478701D03*
Y1475551D03*
Y1472402D03*
Y1469252D03*
Y1466103D03*
Y1462953D03*
Y1459803D03*
Y1456654D03*
Y1453504D03*
Y1450355D03*
Y1447205D03*
Y1444055D03*
Y1440906D03*
Y1437756D03*
Y1434607D03*
Y1431457D03*
X166890Y1470827D03*
Y1467677D03*
Y1464528D03*
Y1461378D03*
Y1458229D03*
Y1455079D03*
X154331Y1544843D03*
Y1541693D03*
Y1538544D03*
Y1535394D03*
Y1532244D03*
Y1529095D03*
Y1525945D03*
Y1522796D03*
Y1519646D03*
Y1516496D03*
Y1513347D03*
Y1510197D03*
Y1507047D03*
Y1503898D03*
Y1865315D03*
Y1862166D03*
Y1859016D03*
Y1855867D03*
Y1852717D03*
Y1849567D03*
Y1846418D03*
Y1843268D03*
Y1840119D03*
Y1836969D03*
Y1833819D03*
Y1830670D03*
Y1827520D03*
X166890Y1866890D03*
Y1863741D03*
Y1860591D03*
X154331Y1937756D03*
Y1934607D03*
Y1931457D03*
Y1928308D03*
Y1925158D03*
Y1922008D03*
Y1918859D03*
Y1915709D03*
Y1912559D03*
Y1909410D03*
Y1906260D03*
Y1903111D03*
Y1899961D03*
Y1896811D03*
Y1893662D03*
Y1890512D03*
Y1887363D03*
Y1884213D03*
Y1881063D03*
Y1877914D03*
Y1874764D03*
Y1871615D03*
Y1868465D03*
X166890Y1876339D03*
Y1873189D03*
Y1870040D03*
X154331Y1950355D03*
Y1947205D03*
Y1944056D03*
Y1940906D03*
X882677Y265315D03*
Y262165D03*
Y259015D03*
Y255866D03*
Y252716D03*
Y249567D03*
Y246417D03*
Y243267D03*
Y240118D03*
Y236968D03*
Y233819D03*
Y230669D03*
Y227519D03*
Y224370D03*
Y221220D03*
Y218071D03*
Y214921D03*
Y211771D03*
Y208622D03*
Y205472D03*
X895236Y254291D03*
Y251141D03*
Y247992D03*
Y244842D03*
Y241693D03*
Y238543D03*
X882677Y328307D03*
Y325157D03*
Y322008D03*
Y318858D03*
Y315708D03*
Y312559D03*
Y309409D03*
Y306260D03*
Y303110D03*
Y299960D03*
Y296811D03*
Y293661D03*
Y290511D03*
Y287362D03*
Y284212D03*
Y281063D03*
Y277913D03*
Y274763D03*
Y271614D03*
Y268464D03*
Y629882D03*
Y626732D03*
Y623583D03*
Y620433D03*
Y617283D03*
Y614134D03*
Y610984D03*
Y702323D03*
Y699173D03*
Y696023D03*
Y692874D03*
Y689724D03*
Y686575D03*
Y683425D03*
Y680275D03*
Y677126D03*
Y673976D03*
Y670827D03*
Y667677D03*
Y664527D03*
Y661378D03*
Y658228D03*
Y655079D03*
Y651929D03*
Y648779D03*
Y645630D03*
Y642480D03*
Y639331D03*
Y636181D03*
Y633031D03*
X895236Y659803D03*
Y656653D03*
Y653504D03*
Y650354D03*
Y647205D03*
Y644055D03*
X882677Y733819D03*
Y730669D03*
Y727520D03*
Y724370D03*
Y721220D03*
Y718071D03*
Y714921D03*
Y711772D03*
Y708622D03*
Y705472D03*
Y1063740D03*
Y1060591D03*
Y1057441D03*
Y1054291D03*
Y1051142D03*
Y1047992D03*
Y1044843D03*
Y1041693D03*
Y1038543D03*
Y1035394D03*
Y1032244D03*
Y1029095D03*
Y1025945D03*
Y1022795D03*
Y1019646D03*
Y1016496D03*
X895236Y1065315D03*
Y1062165D03*
Y1059016D03*
Y1055866D03*
Y1052717D03*
Y1049567D03*
X882677Y1139331D03*
Y1136181D03*
Y1133032D03*
Y1129882D03*
Y1126732D03*
Y1123583D03*
Y1120433D03*
Y1117284D03*
Y1114134D03*
Y1110984D03*
Y1107835D03*
Y1104685D03*
Y1101535D03*
Y1098386D03*
Y1095236D03*
Y1092087D03*
Y1088937D03*
Y1085787D03*
Y1082638D03*
Y1079488D03*
Y1076339D03*
Y1073189D03*
Y1070039D03*
Y1066890D03*
Y1428307D03*
Y1425158D03*
Y1422008D03*
Y1500748D03*
Y1497599D03*
Y1494449D03*
Y1491299D03*
Y1488150D03*
Y1485000D03*
Y1481851D03*
Y1478701D03*
Y1475551D03*
Y1472402D03*
Y1469252D03*
Y1466103D03*
Y1462953D03*
Y1459803D03*
Y1456654D03*
Y1453504D03*
Y1450355D03*
Y1447205D03*
Y1444055D03*
Y1440906D03*
Y1437756D03*
Y1434607D03*
Y1431457D03*
X895236Y1470827D03*
Y1467677D03*
Y1464528D03*
Y1461378D03*
Y1458229D03*
Y1455079D03*
X882677Y1544843D03*
Y1541693D03*
Y1538544D03*
Y1535394D03*
Y1532244D03*
Y1529095D03*
Y1525945D03*
Y1522796D03*
Y1519646D03*
Y1516496D03*
Y1513347D03*
Y1510197D03*
Y1507047D03*
Y1503898D03*
Y1865315D03*
Y1862166D03*
Y1859016D03*
Y1855867D03*
Y1852717D03*
Y1849567D03*
Y1846418D03*
Y1843268D03*
Y1840119D03*
Y1836969D03*
Y1833819D03*
Y1830670D03*
Y1827520D03*
X895236Y1866890D03*
Y1863741D03*
Y1860591D03*
X882677Y1937756D03*
Y1934607D03*
Y1931457D03*
Y1928308D03*
Y1925158D03*
Y1922008D03*
Y1918859D03*
Y1915709D03*
Y1912559D03*
Y1909410D03*
Y1906260D03*
Y1903111D03*
Y1899961D03*
Y1896811D03*
Y1893662D03*
Y1890512D03*
Y1887363D03*
Y1884213D03*
Y1881063D03*
Y1877914D03*
Y1874764D03*
Y1871615D03*
Y1868465D03*
X895236Y1876339D03*
Y1873189D03*
Y1870040D03*
X882677Y1950355D03*
Y1947205D03*
Y1944056D03*
Y1940906D03*
G54D61*
X113957Y1488286D03*
Y1490846D03*
Y1493406D03*
Y1495966D03*
X181318Y547147D03*
Y544587D03*
Y542027D03*
Y539467D03*
X165138D03*
Y542027D03*
Y544587D03*
Y547147D03*
X130137Y1495966D03*
Y1493406D03*
Y1490846D03*
Y1488286D03*
X836830Y191633D03*
Y189073D03*
X820650D03*
Y191633D03*
X836830Y196753D03*
Y194193D03*
X820650D03*
Y196753D03*
X836830Y1810927D03*
Y1808367D03*
Y1805807D03*
Y1803247D03*
X820650D03*
Y1805807D03*
Y1808367D03*
Y1810927D03*
G54D70*
X300000Y585500D03*
Y1421500D03*
G54D25*
X36200Y1823200D03*
Y1819700D03*
X155300Y569500D03*
X348300Y352500D03*
X383800D03*
X356300D03*
X391800D03*
X377300Y782500D03*
X385300D03*
X391800Y806500D03*
X383800Y1154000D03*
X391800D03*
X348300Y1652500D03*
X356300D03*
X388800Y1676500D03*
X389800Y1723500D03*
X918300Y1719000D03*
G54D43*
X63500Y245215D03*
X59625Y237715D03*
X67375D03*
X63500Y650727D03*
X59625Y643227D03*
X67375D03*
X67000Y1058250D03*
X63125Y1050750D03*
X70875D03*
X63500Y1461750D03*
X59625Y1454250D03*
X67375D03*
X101300Y1860650D03*
X97425Y1853150D03*
X105175D03*
X73100Y1867150D03*
X69225Y1859650D03*
X76975D03*
X136500Y156250D03*
X132625Y148750D03*
X140375D03*
X144525Y412850D03*
X152275D03*
X148400Y420350D03*
X121625Y556250D03*
X129375D03*
X125500Y563750D03*
X148400Y825850D03*
X144525Y818350D03*
X152275D03*
X151500Y971250D03*
X147625Y963750D03*
X155375D03*
X148700Y1231350D03*
X144825Y1223850D03*
X152575D03*
X140500Y1371785D03*
X136625Y1364285D03*
X144375D03*
X149900Y1636850D03*
X146025Y1629350D03*
X153775D03*
X197000Y46250D03*
X193125Y38750D03*
X200875D03*
X876161Y163411D03*
X880036Y155911D03*
X872286D03*
X869000Y547215D03*
X872875Y539715D03*
X865125D03*
X878375Y555715D03*
X870625D03*
X874500Y563215D03*
X869000Y952727D03*
X872875Y945227D03*
X865125D03*
X874500Y968727D03*
X878375Y961227D03*
X870625D03*
X869000Y1358238D03*
X872875Y1350738D03*
X865125D03*
X874500Y1374238D03*
X878375Y1366738D03*
X870625D03*
X869000Y1763750D03*
X865125Y1756250D03*
X872875D03*
X874500Y1779750D03*
X870625Y1772250D03*
X878375D03*
G54D16*
X39086Y650614D03*
X37657Y1125065D03*
X38925Y1589682D03*
X37500Y1581000D03*
X98037Y14136D03*
X87500Y202000D03*
X74711Y246388D03*
X87589Y225909D03*
X56500Y216612D03*
X87600Y209868D03*
X111436Y260164D03*
X86000Y253465D03*
X72000D03*
X64734Y217647D03*
X59750Y223465D03*
X70819Y230822D03*
X97731Y234237D03*
X106782Y268794D03*
X80300Y397700D03*
X90800D03*
X85950Y341250D03*
X90700Y349600D03*
X110600Y396300D03*
X93825Y377775D03*
X65300Y396800D03*
X108000Y456012D03*
Y448512D03*
X86500Y608100D03*
X82962Y616638D03*
X64734Y623159D03*
X61523Y630374D03*
X74711Y651900D03*
X87589Y631421D03*
X86000Y658977D03*
X72000D03*
X70621Y636334D03*
X97731Y639749D03*
X41901Y716960D03*
X44576Y724360D03*
X85950Y746750D03*
X90700Y755100D03*
X81300Y803600D03*
X89800Y803500D03*
X43555Y776945D03*
X111200Y802054D03*
X93825Y783275D03*
X70150Y803150D03*
X108000Y861524D03*
Y854024D03*
X86000Y1014200D03*
X97812Y1066417D03*
X88000Y1037507D03*
X82962Y1022149D03*
X86000Y1064488D03*
X72000D03*
X64734Y1028670D03*
X64500Y1037500D03*
X70875Y1044000D03*
X97731Y1045260D03*
X41000Y1070000D03*
X42286Y1104286D03*
X41840Y1115552D03*
X45000Y1076500D03*
X83000Y1208600D03*
X90800D03*
X40097Y1154992D03*
X85950Y1152650D03*
X90700Y1161000D03*
X111000Y1207800D03*
X93825Y1188775D03*
X68150Y1208200D03*
X108000Y1267036D03*
Y1259536D03*
X87500Y1420500D03*
X82962Y1427661D03*
X82137Y1476495D03*
X104000Y1490500D03*
Y1498500D03*
X87589Y1442444D03*
X86000Y1470000D03*
X72000D03*
X64734Y1434182D03*
X62000Y1441800D03*
X70273Y1447357D03*
X97731Y1450772D03*
X85250Y1548750D03*
X90300Y1557100D03*
X42855Y1554900D03*
X39800Y1547400D03*
X78100Y1614500D03*
X86500Y1614700D03*
X47254Y1587961D03*
X51718Y1595562D03*
X111000Y1613200D03*
X103025Y1589654D03*
X83200Y1588650D03*
X63200Y1613300D03*
X108000Y1672548D03*
Y1665048D03*
X88100Y1825000D03*
X79500Y1841400D03*
X82964Y1831400D03*
X90749Y1860311D03*
X93200Y1867400D03*
X65100Y1838100D03*
X62900Y1826400D03*
X105350Y1846300D03*
X83467Y1862457D03*
X109100Y1936300D03*
X83911Y1886506D03*
X55750Y1932750D03*
X109500Y1947700D03*
X60500Y1941100D03*
X60600Y1970300D03*
X80600Y1964000D03*
X41700Y1969400D03*
X130500Y45400D03*
X146000Y41900D03*
X180850Y22721D03*
X165700Y37800D03*
X113200Y59950D03*
X120700D03*
X112800Y49200D03*
X181387Y158953D03*
X175400Y152000D03*
X118832Y152559D03*
X141500Y140500D03*
X182582Y135000D03*
X158497Y163411D03*
X181404Y142546D03*
X155421Y142657D03*
X136795Y319578D03*
Y327078D03*
X120370Y331567D03*
X152300Y370400D03*
X164300Y377200D03*
X129975Y396346D03*
X113650Y378779D03*
X133100Y379700D03*
X149800Y397350D03*
X158150Y434350D03*
X153400Y426000D03*
X115800Y444600D03*
X141321Y541250D03*
X169000Y533500D03*
X176657Y531625D03*
X144750Y549500D03*
X181387Y564465D03*
X162300Y558100D03*
X135000Y570000D03*
X152500Y774500D03*
X136395Y725090D03*
Y732590D03*
X127500Y737100D03*
X153200Y783600D03*
X158150Y839850D03*
X153400Y831100D03*
X130350Y802221D03*
X113650Y784279D03*
X132900Y783900D03*
X150175Y803225D03*
X117000Y849400D03*
X183838Y968275D03*
X172705Y952750D03*
X171477Y965000D03*
X150000Y955000D03*
X161226Y971250D03*
X161512Y963755D03*
X135895Y1130602D03*
Y1138102D03*
X153400Y1189700D03*
X166100Y1189800D03*
X127500Y1142500D03*
X130350Y1207721D03*
X113650Y1189779D03*
X133100Y1191700D03*
X150175Y1208725D03*
X158450Y1245350D03*
X153700Y1237000D03*
X116300Y1255500D03*
X144375Y1357194D03*
X181404Y1357558D03*
X155000Y1357835D03*
X181300Y1374800D03*
X175554Y1367159D03*
X181500Y1382400D03*
X158497Y1379946D03*
X169100Y1371600D03*
X114000Y1482000D03*
X122000D03*
X130000D03*
X135695Y1536114D03*
Y1543614D03*
X122500Y1547400D03*
X155000Y1583800D03*
X154900Y1591300D03*
Y1642500D03*
X130350Y1613221D03*
X123042Y1583449D03*
X150175Y1614225D03*
X159650Y1650850D03*
X121950Y1661250D03*
X181387Y1781000D03*
X175000Y1774500D03*
X171506Y1763994D03*
X165000Y1774000D03*
X131795Y1932826D03*
Y1940326D03*
X138100Y1946000D03*
X143450Y1975664D03*
X200675Y23725D03*
X206750Y60250D03*
X201600Y51900D03*
X186487Y164453D03*
X203154Y139453D03*
X187608Y154749D03*
X186400Y368300D03*
X193750Y535250D03*
X194000Y527750D03*
Y555125D03*
X191500Y543500D03*
X186487Y569965D03*
X187500Y559000D03*
X217200Y565700D03*
X187800Y775400D03*
X212300Y961000D03*
X186487Y975477D03*
X191000Y964300D03*
X191500Y942500D03*
X188000Y1179500D03*
X186100Y1346600D03*
X199900Y1346488D03*
X186700Y1585700D03*
X201447Y1751500D03*
X228181Y1772100D03*
X186400Y1786700D03*
X190266Y1776603D03*
X194750Y1762000D03*
X210500Y1761400D03*
X287951Y93246D03*
X315100Y403400D03*
X291955Y505017D03*
X315400Y598400D03*
X314000Y587000D03*
X320900Y593000D03*
X306500Y568400D03*
X315000Y571000D03*
Y578500D03*
X314000Y834000D03*
X314600Y1204800D03*
X313500Y1406300D03*
X301500Y1407500D03*
X307400Y1400800D03*
X285100Y1412200D03*
X285700Y1404100D03*
X293200Y1406100D03*
X272722Y1584801D03*
X276500Y1709400D03*
X269000Y1709516D03*
X315200Y1704900D03*
X287500Y1783000D03*
X279500D03*
X271500D03*
X276500Y1740000D03*
X271000Y1745500D03*
X282000D03*
X352500Y81500D03*
X348500Y118500D03*
X355000Y112000D03*
X363500Y81500D03*
X367250Y63000D03*
X368800Y88300D03*
X368350Y104650D03*
X380250Y336100D03*
X344750D03*
X388250Y336000D03*
X352750D03*
X381500Y357500D03*
X346000D03*
X343500Y393000D03*
X345900Y376000D03*
X333300Y403400D03*
X339000Y379000D03*
X343000Y385500D03*
X355250Y463900D03*
X390750D03*
X354000Y442500D03*
X389500D03*
X347250Y464000D03*
X382750D03*
X333500Y421000D03*
Y413000D03*
X340500Y425000D03*
X373750Y766100D03*
X381750Y766000D03*
X375100Y787700D03*
X333500Y843000D03*
X343500Y823000D03*
X345300Y804400D03*
X379600Y795300D03*
X333800Y833000D03*
X339000Y809000D03*
X343000Y815500D03*
X355250Y893900D03*
X390750D03*
X354000Y872500D03*
X389500D03*
X347250Y894000D03*
X382750D03*
X333500Y851000D03*
X340500Y855000D03*
X348861Y1070104D03*
X380250Y1137600D03*
X388250Y1137500D03*
X381500Y1159000D03*
X343500Y1194500D03*
X345600Y1176100D03*
X385900Y1166100D03*
X334500Y1204250D03*
X339000Y1180500D03*
X343000Y1187000D03*
X355029Y1265402D03*
X390750Y1265400D03*
X354000Y1244000D03*
X389500D03*
X347250Y1265500D03*
X382750D03*
X333500Y1222500D03*
Y1214500D03*
X340500Y1226500D03*
X344750Y1636100D03*
X352750Y1636000D03*
X346000Y1657500D03*
X333500Y1721000D03*
Y1713000D03*
X344000Y1693600D03*
X346000Y1676500D03*
X333600Y1703500D03*
X339100Y1679600D03*
X342700Y1686200D03*
X355250Y1763900D03*
X354000Y1742500D03*
X347250Y1764000D03*
X340500Y1725000D03*
X406000Y399000D03*
X474300Y423688D03*
X433900Y809250D03*
X412500Y810500D03*
X434000Y817250D03*
X433900Y1211750D03*
X412500Y1213000D03*
X434000Y1219750D03*
X433900Y1710250D03*
X412500Y1711500D03*
X434000Y1718250D03*
X486363Y932790D03*
X668643Y131315D03*
X763200Y1698600D03*
X820500Y183000D03*
X828500D03*
X836500D03*
X810500Y191500D03*
Y199500D03*
X814250Y341250D03*
X819000Y349600D03*
X820325Y377775D03*
X814250Y746750D03*
X819000Y755100D03*
X820325Y783275D03*
X814250Y1152250D03*
X819000Y1160600D03*
X820325Y1188775D03*
X814250Y1557750D03*
X819200Y1566100D03*
X820325Y1594275D03*
X826888Y1714000D03*
X835888Y1716500D03*
X829888Y1721000D03*
X819000Y1797000D03*
X829500D03*
X837500D03*
X810500Y1805500D03*
Y1813500D03*
X779089Y1931757D03*
X783939Y1940107D03*
X835800Y1948500D03*
X835000Y1941000D03*
X788389Y1969286D03*
X808339Y1962507D03*
X768564Y1968282D03*
X909733Y158953D03*
X904728Y151181D03*
X883412Y149000D03*
X909881Y131990D03*
X879000Y169500D03*
X910750Y141223D03*
X884000Y140013D03*
X863941Y319578D03*
Y327078D03*
X850125Y330750D03*
X882500Y367000D03*
X894900Y377300D03*
X840150Y378779D03*
X861890Y383014D03*
X903728Y556693D03*
X881500Y548965D03*
X907492Y536837D03*
X909750Y546735D03*
X880636Y541514D03*
X909733Y564465D03*
X886843Y568923D03*
X882000Y773000D03*
X863841Y725090D03*
Y732590D03*
X851150Y736750D03*
X894800Y783900D03*
X840150Y784279D03*
X859737Y789667D03*
X909733Y969977D03*
X903728Y962205D03*
X881500Y954477D03*
X890550Y957450D03*
X908177Y942729D03*
X879800Y975800D03*
X909750Y952247D03*
X880636Y947026D03*
X864241Y1130602D03*
Y1138102D03*
X880500Y1178500D03*
X886400Y1185000D03*
X849550Y1142150D03*
X840150Y1189779D03*
X860272Y1194370D03*
X852898Y1249029D03*
X908530Y1348458D03*
X909750Y1357758D03*
X880636Y1352537D03*
X909733Y1375488D03*
X903900Y1367659D03*
X881500Y1359988D03*
X880100Y1380100D03*
X864441Y1536114D03*
Y1543614D03*
X850550Y1547750D03*
X883000Y1582500D03*
X885300Y1590300D03*
X840150Y1595279D03*
X858185Y1601013D03*
X911800Y1684000D03*
X909700Y1719000D03*
X879100Y1715100D03*
X896500Y1696300D03*
X906000Y1703400D03*
X889600Y1691900D03*
X904276Y1696100D03*
X903728Y1773228D03*
X881500Y1765500D03*
X909733Y1781000D03*
X898089Y1745256D03*
X894484Y1722200D03*
X886843Y1785458D03*
X909750Y1763270D03*
X881636Y1757549D03*
X862241Y1934326D03*
Y1941826D03*
X856900Y1947600D03*
X871750Y1975500D03*
X914833Y164453D03*
X931500Y139453D03*
X915037Y153502D03*
X915900Y368600D03*
X931500Y544965D03*
X916600Y556600D03*
X914833Y569965D03*
X915800Y774600D03*
X914833Y975477D03*
X931500Y950477D03*
X914646Y964214D03*
X919100Y1180600D03*
X931500Y1355988D03*
X914833Y1380988D03*
X915037Y1370037D03*
X969000Y1641500D03*
X976000Y1636000D03*
X918600Y1584600D03*
X969500Y1676500D03*
X916200Y1708700D03*
X914833Y1786500D03*
X913923Y1752000D03*
X931500Y1761500D03*
X916100Y1773800D03*
G54D53*
X107750Y373900D03*
X100250Y377775D03*
Y370025D03*
Y775525D03*
X107750Y779400D03*
X100250Y783275D03*
X107750Y1184900D03*
X100250Y1188775D03*
Y1181025D03*
X109125Y1588650D03*
Y1580900D03*
X97125Y1584775D03*
X89625Y1588650D03*
Y1580900D03*
X74450Y1965200D03*
X66950Y1969075D03*
Y1961325D03*
X55350Y1965300D03*
X47850Y1969175D03*
Y1961425D03*
X127250Y373900D03*
X119750Y377775D03*
Y370025D03*
Y775525D03*
X127250Y779400D03*
X119750Y783275D03*
X127250Y1184900D03*
X119750Y1188775D03*
Y1181025D03*
X116625Y1584775D03*
X834250Y373900D03*
X826750Y370025D03*
Y377775D03*
Y775525D03*
X834250Y779400D03*
X826750Y783275D03*
X834250Y1184900D03*
X826750Y1181025D03*
Y1188775D03*
X834250Y1590400D03*
X826750Y1586525D03*
Y1594275D03*
X782489Y1964407D03*
X774989Y1960532D03*
Y1968282D03*
X801989Y1964407D03*
X794489Y1960532D03*
Y1968282D03*
X876750Y145000D03*
X869250Y141125D03*
Y148875D03*
X853750Y373900D03*
X846250Y370025D03*
Y377775D03*
Y775525D03*
X853750Y779400D03*
X846250Y783275D03*
X853750Y1184900D03*
X846250Y1181025D03*
Y1188775D03*
X853750Y1590400D03*
X846250Y1586525D03*
Y1594275D03*
G54D62*
X85640Y1847150D03*
X88200D03*
X90760D03*
Y1853650D03*
X85640D03*
X150940Y556750D03*
X153500D03*
X156060D03*
Y563250D03*
X150940D03*
X187440Y949750D03*
X190000D03*
X192560D03*
Y956250D03*
X187440D03*
G54D35*
X78839Y41161D03*
Y46161D03*
Y51161D03*
Y56161D03*
Y61161D03*
Y66161D03*
Y71161D03*
Y76161D03*
Y81161D03*
Y86161D03*
Y91161D03*
Y96161D03*
Y101161D03*
Y106161D03*
Y111161D03*
Y136161D03*
Y141161D03*
Y146161D03*
Y151161D03*
Y156161D03*
Y161161D03*
Y166161D03*
Y446673D03*
Y451673D03*
Y456673D03*
Y461673D03*
Y466673D03*
Y471673D03*
Y476673D03*
Y481673D03*
Y486673D03*
Y491673D03*
Y496673D03*
Y501673D03*
Y506673D03*
Y511673D03*
Y516673D03*
Y541673D03*
Y546673D03*
Y551673D03*
Y556673D03*
Y561673D03*
Y566673D03*
Y571673D03*
Y852185D03*
Y857185D03*
Y862185D03*
Y867185D03*
Y872185D03*
Y877185D03*
Y882185D03*
Y887185D03*
Y892185D03*
Y897185D03*
Y902185D03*
Y907185D03*
Y912185D03*
Y917185D03*
Y922185D03*
Y947185D03*
Y952185D03*
Y957185D03*
Y962185D03*
Y967185D03*
Y972185D03*
Y977185D03*
Y1257697D03*
Y1262697D03*
Y1267697D03*
Y1272697D03*
Y1277697D03*
Y1282697D03*
Y1287697D03*
Y1292697D03*
Y1297697D03*
Y1302697D03*
Y1307697D03*
Y1312697D03*
Y1317697D03*
Y1322697D03*
Y1327697D03*
Y1352697D03*
Y1357697D03*
Y1362697D03*
Y1367697D03*
Y1372697D03*
Y1377697D03*
Y1382697D03*
Y1663209D03*
Y1668209D03*
Y1673209D03*
Y1678209D03*
Y1683209D03*
Y1688209D03*
Y1693209D03*
Y1698209D03*
Y1703209D03*
Y1708209D03*
Y1713209D03*
Y1718209D03*
Y1723209D03*
Y1728209D03*
Y1733209D03*
Y1758209D03*
Y1763209D03*
Y1768209D03*
Y1773209D03*
Y1778209D03*
Y1783209D03*
Y1788209D03*
X165256Y263917D03*
Y258917D03*
Y233917D03*
Y228917D03*
Y223917D03*
Y218917D03*
Y213917D03*
Y208917D03*
Y203917D03*
Y328917D03*
Y323917D03*
Y318917D03*
Y313917D03*
Y308917D03*
Y303917D03*
Y298917D03*
Y293917D03*
Y288917D03*
Y283917D03*
Y278917D03*
Y273917D03*
Y268917D03*
Y629429D03*
Y624429D03*
Y619429D03*
Y614429D03*
Y609429D03*
Y699429D03*
Y694429D03*
Y689429D03*
Y684429D03*
Y679429D03*
Y674429D03*
Y669429D03*
Y664429D03*
Y639429D03*
Y634429D03*
Y734429D03*
Y729429D03*
Y724429D03*
Y719429D03*
Y714429D03*
Y709429D03*
Y704429D03*
Y1044941D03*
Y1039941D03*
Y1034941D03*
Y1029941D03*
Y1024941D03*
Y1019941D03*
Y1014941D03*
Y1134941D03*
Y1129941D03*
Y1124941D03*
Y1119941D03*
Y1114941D03*
Y1109941D03*
Y1104941D03*
Y1099941D03*
Y1094941D03*
Y1089941D03*
Y1084941D03*
Y1079941D03*
Y1074941D03*
Y1069941D03*
Y1139941D03*
Y1430453D03*
Y1425453D03*
Y1420453D03*
Y1500453D03*
Y1495453D03*
Y1490453D03*
Y1485453D03*
Y1480453D03*
Y1475453D03*
Y1450453D03*
Y1445453D03*
Y1440453D03*
Y1435453D03*
Y1545453D03*
Y1540453D03*
Y1535453D03*
Y1530453D03*
Y1525453D03*
Y1520453D03*
Y1515453D03*
Y1510453D03*
Y1505453D03*
Y1855965D03*
Y1850965D03*
Y1845965D03*
Y1840965D03*
Y1835965D03*
Y1830965D03*
Y1825965D03*
Y1935965D03*
Y1930965D03*
Y1925965D03*
Y1920965D03*
Y1915965D03*
Y1910965D03*
Y1905965D03*
Y1900965D03*
Y1895965D03*
Y1890965D03*
Y1885965D03*
Y1880965D03*
Y1950965D03*
Y1945965D03*
Y1940965D03*
X893602Y263917D03*
Y258917D03*
Y233917D03*
Y228917D03*
Y223917D03*
Y218917D03*
Y213917D03*
Y208917D03*
Y203917D03*
Y328917D03*
Y323917D03*
Y318917D03*
Y313917D03*
Y308917D03*
Y303917D03*
Y298917D03*
Y293917D03*
Y288917D03*
Y283917D03*
Y278917D03*
Y273917D03*
Y268917D03*
Y629429D03*
Y624429D03*
Y619429D03*
Y614429D03*
Y609429D03*
Y699429D03*
Y694429D03*
Y689429D03*
Y684429D03*
Y679429D03*
Y674429D03*
Y669429D03*
Y664429D03*
Y639429D03*
Y634429D03*
Y734429D03*
Y729429D03*
Y724429D03*
Y719429D03*
Y714429D03*
Y709429D03*
Y704429D03*
Y1044941D03*
Y1039941D03*
Y1034941D03*
Y1029941D03*
Y1024941D03*
Y1019941D03*
Y1014941D03*
Y1134941D03*
Y1129941D03*
Y1124941D03*
Y1119941D03*
Y1114941D03*
Y1109941D03*
Y1104941D03*
Y1099941D03*
Y1094941D03*
Y1089941D03*
Y1084941D03*
Y1079941D03*
Y1074941D03*
Y1069941D03*
Y1139941D03*
Y1430453D03*
Y1425453D03*
Y1420453D03*
Y1500453D03*
Y1495453D03*
Y1490453D03*
Y1485453D03*
Y1480453D03*
Y1475453D03*
Y1450453D03*
Y1445453D03*
Y1440453D03*
Y1435453D03*
Y1545453D03*
Y1540453D03*
Y1535453D03*
Y1530453D03*
Y1525453D03*
Y1520453D03*
Y1515453D03*
Y1510453D03*
Y1505453D03*
Y1855965D03*
Y1850965D03*
Y1845965D03*
Y1840965D03*
Y1835965D03*
Y1830965D03*
Y1825965D03*
Y1935965D03*
Y1930965D03*
Y1925965D03*
Y1920965D03*
Y1915965D03*
Y1910965D03*
Y1905965D03*
Y1900965D03*
Y1895965D03*
Y1890965D03*
Y1885965D03*
Y1880965D03*
Y1950965D03*
Y1945965D03*
Y1940965D03*
G54D80*
X357205Y382585D03*
X359175D03*
X361140D03*
X363110D03*
X365080D03*
X367045D03*
X369015D03*
X370985D03*
X372955D03*
X374920D03*
X376890D03*
X378860D03*
X380825D03*
X382795D03*
Y417415D03*
X380825D03*
X378860D03*
X376890D03*
X374920D03*
X372955D03*
X370985D03*
X369015D03*
X367045D03*
X365080D03*
X363110D03*
X361140D03*
X359175D03*
X357205D03*
Y812585D03*
X359175D03*
X361140D03*
X363110D03*
X365080D03*
X367045D03*
X369015D03*
X370985D03*
X372955D03*
X374920D03*
X376890D03*
X378860D03*
X380825D03*
X382795D03*
Y847415D03*
X380825D03*
X378860D03*
X376890D03*
X374920D03*
X372955D03*
X370985D03*
X369015D03*
X367045D03*
X365080D03*
X363110D03*
X361140D03*
X359175D03*
X357205D03*
Y1184085D03*
X359175D03*
X361140D03*
X363110D03*
X365080D03*
X367045D03*
X369015D03*
X370985D03*
X372955D03*
X374920D03*
X376890D03*
X378860D03*
X380825D03*
X382795D03*
Y1218915D03*
X380825D03*
X378860D03*
X376890D03*
X374920D03*
X372955D03*
X370985D03*
X369015D03*
X367045D03*
X365080D03*
X363110D03*
X361140D03*
X359175D03*
X357205D03*
Y1682585D03*
X359175D03*
X361140D03*
X363110D03*
X365080D03*
X367045D03*
X369015D03*
X370985D03*
X372955D03*
X374920D03*
X376890D03*
X378860D03*
X380825D03*
X382795D03*
Y1717415D03*
X380825D03*
X378860D03*
X376890D03*
X374920D03*
X372955D03*
X370985D03*
X369015D03*
X367045D03*
X365080D03*
X363110D03*
X361140D03*
X359175D03*
X357205D03*
G54D71*
X304921Y1413400D03*
X295079D03*
Y1429600D03*
X304921D03*
X355235Y382083D03*
X384765D03*
Y417917D03*
X355235D03*
Y812083D03*
X384765D03*
Y847917D03*
X355235D03*
Y1183583D03*
X384765D03*
Y1219417D03*
X355235D03*
Y1682083D03*
X384765D03*
Y1717917D03*
X355235D03*
X896453Y1703894D03*
X890547D03*
Y1716106D03*
X896453D03*
G54D26*
X37100Y1832100D03*
Y1827300D03*
X325900Y583400D03*
G54D44*
X92800Y210000D03*
X77300Y253465D03*
X92800Y214465D03*
X78550Y239715D03*
X92800Y201000D03*
Y205500D03*
X96000Y349000D03*
X92800Y615500D03*
Y619977D03*
Y611000D03*
X77300Y658977D03*
X78550Y645227D03*
X96000Y754500D03*
X92800Y1021000D03*
X77300Y1064488D03*
X92800Y1025488D03*
Y1016500D03*
X96000Y1160400D03*
X92800Y1426500D03*
Y1417500D03*
Y1422000D03*
X77300Y1470000D03*
X92800Y1431000D03*
X95300Y1556500D03*
X109100Y1548200D03*
X93800Y1830000D03*
X101900Y1839900D03*
X93800Y1821500D03*
X68275Y1823331D03*
X70110Y1837270D03*
X93787Y1825915D03*
X65800Y1940500D03*
X177954Y147453D03*
X132675Y162475D03*
X167656Y168811D03*
X124800Y321000D03*
Y326000D03*
X154750Y397350D03*
X181800Y531000D03*
Y527000D03*
X124800Y726500D03*
Y731500D03*
X176800Y963500D03*
X157046Y976999D03*
X124800Y1132000D03*
Y1137000D03*
X155125Y1208725D03*
X177954Y1362488D03*
X136675Y1378010D03*
X167674Y1385323D03*
X124800Y1537500D03*
Y1542500D03*
X155125Y1614225D03*
X181646Y1774500D03*
X167492Y1790692D03*
X123100Y1934100D03*
Y1939100D03*
X205625Y23725D03*
X192300Y167000D03*
Y158000D03*
Y162500D03*
X191800Y573500D03*
X209300Y569000D03*
X191800Y564500D03*
Y569000D03*
X192300Y978500D03*
X203900Y960977D03*
X192300Y969500D03*
X203900Y965477D03*
X192300Y974000D03*
X186800Y1382000D03*
Y1373000D03*
Y1377500D03*
X191300Y1790500D03*
X216000Y1772100D03*
X244900Y1769900D03*
X191300Y1781500D03*
X216000Y1776200D03*
X191300Y1786000D03*
X324800Y413000D03*
X329300Y570580D03*
Y578600D03*
X325800Y605000D03*
Y593000D03*
X320300Y572500D03*
Y576500D03*
X325800Y601000D03*
X324800Y843000D03*
Y1214500D03*
X276800Y1407500D03*
X319800Y1429700D03*
Y1417500D03*
Y1425700D03*
Y1405400D03*
Y1413500D03*
Y1437700D03*
X324800Y1713000D03*
X276800Y1722000D03*
X363800Y68500D03*
X344800Y341000D03*
X380300D03*
X334800Y393000D03*
X330800Y373000D03*
X352800Y341000D03*
X388300D03*
X373800Y771000D03*
X381800D03*
X334800Y823000D03*
X330800Y803000D03*
X397300Y840500D03*
X380300Y1142500D03*
X330800Y1174500D03*
X334800Y1194500D03*
X398800Y1192000D03*
X388300Y1142500D03*
X344800Y1641000D03*
X352800D03*
X330800Y1673000D03*
X334800Y1695000D03*
X421300Y817500D03*
Y809500D03*
Y1212000D03*
Y1220000D03*
Y1718500D03*
Y1710500D03*
X824300Y349000D03*
Y754500D03*
Y1160000D03*
Y1565500D03*
X789139Y1939507D03*
X907300Y146453D03*
X852800Y321000D03*
Y326000D03*
X906300Y551965D03*
X895976Y574422D03*
X852800Y726500D03*
Y731500D03*
X906300Y957477D03*
X852800Y1132000D03*
Y1137000D03*
X906300Y1362988D03*
X852800Y1537500D03*
Y1542500D03*
X911800Y1695000D03*
Y1703000D03*
X906300Y1768500D03*
X895492Y1790816D03*
X851800Y1935800D03*
X847900Y1949700D03*
X851800Y1940800D03*
X919800Y164453D03*
Y155500D03*
Y160000D03*
Y569965D03*
Y561000D03*
Y565500D03*
Y975477D03*
Y966500D03*
Y971000D03*
Y1380988D03*
Y1372000D03*
Y1376500D03*
Y1786500D03*
Y1777500D03*
Y1782000D03*
G54D17*
X25000Y988000D03*
X27825Y995000D03*
X78675Y380704D03*
X47500Y660500D03*
X45000Y1057000D03*
X77607Y1565391D03*
X183344Y808200D03*
X126221Y861250D03*
Y853750D03*
X163170Y1210999D03*
X117387Y1536250D03*
Y1543750D03*
X122844Y1672400D03*
X130344D03*
X213244Y23725D03*
X243156Y382060D03*
X235656D03*
X228156Y438500D03*
X220656D03*
X206700Y575000D03*
X190844Y808200D03*
X242700Y1266656D03*
Y1259156D03*
X232344Y1740000D03*
X239844D03*
X284000Y541344D03*
Y548844D03*
X317156Y1193440D03*
X324656D03*
X276344Y1183060D03*
X268844D03*
X401500Y395500D03*
X393500Y422000D03*
X401500Y830000D03*
X393500Y852000D03*
X402000Y1196500D03*
X396637Y1176000D03*
X358156Y1411000D03*
X350656D03*
X402000Y1695000D03*
X379500Y1673750D03*
X427500Y297156D03*
Y304656D03*
X412500Y1130750D03*
Y1138250D03*
X438656Y1669000D03*
X431156D03*
X458156Y1743000D03*
X450656D03*
X512656Y623500D03*
X520156D03*
X555000Y524344D03*
Y531844D03*
X807756Y377775D03*
X808256Y783275D03*
X807756Y1188775D03*
Y1594275D03*
X979500Y1669750D03*
Y1662250D03*
G54D63*
X87200Y1960400D03*
Y1968000D03*
X129725Y1581125D03*
Y1588725D03*
X388000Y1728700D03*
Y1736300D03*
X835500Y1700200D03*
Y1707800D03*
X827500D03*
Y1700200D03*
X835500Y1734800D03*
Y1727200D03*
X827500D03*
Y1734800D03*
X815339Y1959407D03*
Y1967007D03*
X884500Y1730800D03*
Y1723200D03*
G54D54*
X105025Y401025D03*
X97425D03*
X105200Y805700D03*
X97600D03*
X105100Y1211800D03*
X97500D03*
X105000Y1616700D03*
X97400D03*
X160400Y36600D03*
X152800D03*
X139000Y375300D03*
X146600D03*
X139100Y780600D03*
X146700D03*
X137700Y1185900D03*
X145300D03*
X315200Y422600D03*
X307600D03*
X315500Y853100D03*
X307900D03*
X314800Y1224000D03*
X307200D03*
X315300Y1722100D03*
X307700D03*
X398700Y420500D03*
Y850500D03*
X400700Y1232500D03*
X406300Y420500D03*
Y850500D03*
X408300Y1232500D03*
X866800Y376400D03*
X874400D03*
X866300Y781900D03*
X873900D03*
X866300Y1187400D03*
X873900D03*
X866300Y1594400D03*
X873900D03*
G54D81*
X809000Y1723500D03*
X820000D03*
X809000Y1714500D03*
X820000D03*
X889853Y1660249D03*
X878853D03*
G54D72*
X291900Y1416579D03*
Y1426421D03*
X308100D03*
Y1416579D03*
X352083Y385235D03*
X387917D03*
X352083Y414765D03*
X387917D03*
X352083Y844765D03*
Y815235D03*
X387917D03*
Y844765D03*
X352083Y1186735D03*
X387917D03*
X352083Y1216265D03*
X387917D03*
X352083Y1714765D03*
Y1685235D03*
X387917D03*
Y1714765D03*
X887394Y1707047D03*
Y1712953D03*
X899606D03*
Y1707047D03*
G54D27*
X31500Y1832100D03*
Y1827300D03*
X320300Y583400D03*
G54D45*
X96200Y210000D03*
X80700Y253465D03*
X96200Y214465D03*
X81950Y239715D03*
X96200Y201000D03*
Y205500D03*
X99400Y349000D03*
X96200Y615500D03*
Y619977D03*
Y611000D03*
X80700Y658977D03*
X81950Y645227D03*
X99400Y754500D03*
X96200Y1021000D03*
X80700Y1064488D03*
X96200Y1025488D03*
Y1016500D03*
X99400Y1160400D03*
X96200Y1426500D03*
Y1417500D03*
Y1422000D03*
X80700Y1470000D03*
X96200Y1431000D03*
X98700Y1556500D03*
X97200Y1830000D03*
X105300Y1839900D03*
X97200Y1821500D03*
X71675Y1823331D03*
X73510Y1837270D03*
X97187Y1825915D03*
X69200Y1940500D03*
X181354Y147453D03*
X136075Y162475D03*
X171056Y168811D03*
X128200Y321000D03*
Y326000D03*
X158150Y397350D03*
X128200Y726500D03*
Y731500D03*
X180200Y963500D03*
X160446Y976999D03*
X128200Y1132000D03*
Y1137000D03*
X158525Y1208725D03*
X181354Y1362488D03*
X140075Y1378010D03*
X171074Y1385323D03*
X128200Y1537500D03*
Y1542500D03*
X112500Y1548200D03*
X158525Y1614225D03*
X170892Y1790692D03*
X126500Y1934100D03*
Y1939100D03*
X209025Y23725D03*
X195700Y167000D03*
Y158000D03*
Y162500D03*
X185200Y531000D03*
Y527000D03*
X195200Y573500D03*
X212700Y569000D03*
X195200Y564500D03*
Y569000D03*
X195700Y978500D03*
X207300Y960977D03*
X195700Y969500D03*
X207300Y965477D03*
X195700Y974000D03*
X190200Y1382000D03*
Y1373000D03*
Y1377500D03*
X194700Y1790500D03*
X185046Y1774500D03*
X219400Y1772100D03*
X248300Y1769900D03*
X194700Y1781500D03*
X219400Y1776200D03*
X194700Y1786000D03*
X328200Y413000D03*
X329200Y605000D03*
Y593000D03*
X323700Y572500D03*
Y576500D03*
X329200Y601000D03*
X328200Y843000D03*
Y1214500D03*
X280200Y1407500D03*
X323200Y1429700D03*
Y1417500D03*
Y1425700D03*
Y1405400D03*
Y1413500D03*
Y1437700D03*
X328200Y1713000D03*
X280200Y1722000D03*
X367200Y68500D03*
X348200Y341000D03*
X383700D03*
X338200Y393000D03*
X334200Y373000D03*
X356200Y341000D03*
X391700D03*
X332700Y570580D03*
Y578600D03*
X377200Y771000D03*
X385200D03*
X338200Y823000D03*
X334200Y803000D03*
X400700Y840500D03*
X383700Y1142500D03*
X334200Y1174500D03*
X338200Y1194500D03*
X402200Y1192000D03*
X391700Y1142500D03*
X348200Y1641000D03*
X356200D03*
X334200Y1673000D03*
X338200Y1695000D03*
X424700Y817500D03*
Y809500D03*
Y1212000D03*
Y1220000D03*
Y1718500D03*
Y1710500D03*
X827700Y349000D03*
Y754500D03*
Y1160000D03*
Y1565500D03*
X792539Y1939507D03*
X910700Y146453D03*
X856200Y321000D03*
Y326000D03*
X909700Y551965D03*
X899376Y574422D03*
X856200Y726500D03*
Y731500D03*
X909700Y957477D03*
X856200Y1132000D03*
Y1137000D03*
X909700Y1362988D03*
X856200Y1537500D03*
Y1542500D03*
X909700Y1768500D03*
X898892Y1790816D03*
X855200Y1935800D03*
X851300Y1949700D03*
X855200Y1940800D03*
X923200Y164453D03*
Y155500D03*
Y160000D03*
Y569965D03*
Y561000D03*
Y565500D03*
Y975477D03*
Y966500D03*
Y971000D03*
Y1380988D03*
Y1372000D03*
Y1376500D03*
X915200Y1695000D03*
Y1703000D03*
X923200Y1786500D03*
Y1777500D03*
Y1782000D03*
G54D90*
X916500Y1723250D03*
G54D18*
X31707Y1062791D03*
Y1081291D03*
X41100Y1633650D03*
Y1615150D03*
G54D36*
X72835Y17047D03*
Y190275D03*
Y422559D03*
Y595787D03*
Y828071D03*
Y1001299D03*
Y1233583D03*
Y1406811D03*
Y1639095D03*
Y1812323D03*
X171260Y179803D03*
Y353031D03*
Y585315D03*
Y758543D03*
Y990827D03*
Y1164055D03*
Y1396339D03*
Y1569567D03*
Y1801851D03*
Y1975079D03*
X899606Y179803D03*
Y353031D03*
Y585315D03*
Y758543D03*
Y990827D03*
Y1164055D03*
Y1396339D03*
Y1569567D03*
Y1801851D03*
Y1975079D03*
G54D64*
X308100Y416200D03*
Y846700D03*
X308200Y1217500D03*
X309200Y1715700D03*
X963700Y1661000D03*
Y1671000D03*
X919700Y1695000D03*
G54D46*
X59859Y204971D03*
X91200Y341300D03*
X94500Y369300D03*
X67414Y628262D03*
X91200Y746800D03*
X94500Y774800D03*
X77750Y1049436D03*
X91200Y1152700D03*
X94500Y1180300D03*
X76750Y1455150D03*
X90500Y1548800D03*
X83875Y1580175D03*
X77100Y1846200D03*
X61000Y1932800D03*
X56000Y1880800D03*
X41800Y1960600D03*
X180850Y27650D03*
X125700Y47900D03*
X146400Y136300D03*
X150557D03*
X114295Y331617D03*
X153625Y402425D03*
X129975Y401275D03*
X148400Y430900D03*
X120800Y441100D03*
X122025Y569675D03*
X117945Y737217D03*
X148400Y836400D03*
X154000Y808300D03*
X158500Y804300D03*
X130350Y807150D03*
X122251Y845546D03*
X178000Y952800D03*
X117900Y1142600D03*
X148700Y1241900D03*
X154000Y1213800D03*
X130350Y1212650D03*
X121500Y1252100D03*
X130000Y1473300D03*
X122000D03*
X114000D03*
X149900Y1647400D03*
X154000Y1619300D03*
X130350Y1619150D03*
X117000Y1657800D03*
X170080Y1773528D03*
X204500Y28800D03*
X197000Y56800D03*
X203000Y535300D03*
Y542800D03*
Y527800D03*
X194750Y1753050D03*
X200198Y1758800D03*
X305100Y393100D03*
X309300Y400600D03*
X313000Y562300D03*
X292000Y605300D03*
X284000D03*
X304000D03*
X296000D03*
X316000D03*
X308000D03*
X304500Y822600D03*
X308600Y830100D03*
X305200Y1194050D03*
X309300Y1201550D03*
X303500Y1392300D03*
X311500D03*
X287600Y1441300D03*
X279650D03*
X299600D03*
X291600D03*
X311600D03*
X303600D03*
X306200Y1692550D03*
X310300Y1700050D03*
X291500Y1788300D03*
X283500D03*
X275500D03*
X280500Y1731300D03*
X276500D03*
X272500D03*
X352500Y71800D03*
X378100Y84700D03*
X377500Y101300D03*
X344500Y364300D03*
X359500D03*
X340500D03*
X380000D03*
X395000D03*
X355500D03*
X376000D03*
X391000D03*
X398000Y406800D03*
X382500Y451300D03*
X347000D03*
X390500D03*
X355000D03*
X384500Y794300D03*
X388500D03*
X369500D03*
X373500D03*
X382500Y881300D03*
X347000D03*
X390500D03*
X355000D03*
X380000Y1165800D03*
X391000D03*
X395000D03*
X376000D03*
X382500Y1252800D03*
X347000D03*
X390500D03*
X355000D03*
X355500Y1664300D03*
X340500D03*
X359500D03*
X344500D03*
X379000Y1729300D03*
X347000Y1751300D03*
X355000D03*
X429000Y809300D03*
Y817300D03*
Y1211800D03*
Y1219800D03*
Y1710300D03*
Y1718300D03*
X836500Y174300D03*
X828500D03*
X820500D03*
X819500Y341300D03*
X821000Y369300D03*
X819500Y746800D03*
X821000Y774800D03*
X819500Y1152300D03*
X821000Y1180300D03*
X819500Y1557800D03*
X821000Y1585800D03*
X837500Y1788300D03*
X829500D03*
X819000D03*
X784339Y1931807D03*
X769239Y1959807D03*
X866961Y155961D03*
X844050Y330800D03*
X846200Y736800D03*
X844600Y1142200D03*
X845600Y1547800D03*
X906000Y1687800D03*
X859500Y1699300D03*
X902500Y1727300D03*
X898500D03*
X910500Y1727800D03*
X959000Y1668300D03*
G54D28*
X40184Y1865200D03*
X29216D03*
X40184Y1852900D03*
X29216D03*
X40184Y1840600D03*
X29216D03*
X40184Y1877500D03*
X29216D03*
X878859Y1671037D03*
X889827D03*
X878859Y1683500D03*
X889827D03*
G54D91*
X1023228Y1416024D03*
Y1694212D03*
G54D19*
X33469Y1029523D03*
X269690Y1490152D03*
G54D55*
X107200Y342500D03*
Y347500D03*
Y352500D03*
Y357500D03*
Y748000D03*
Y753000D03*
Y758000D03*
Y763000D03*
Y1153900D03*
Y1158900D03*
Y1163900D03*
Y1168900D03*
X106700Y1554100D03*
Y1559100D03*
Y1564100D03*
Y1569100D03*
X99500Y1939000D03*
Y1934000D03*
X79500D03*
Y1939000D03*
X99500Y1949000D03*
Y1944000D03*
X79500D03*
Y1949000D03*
X165500Y44000D03*
X185500D03*
X165500Y49000D03*
Y54000D03*
Y59000D03*
X185500D03*
Y54000D03*
Y49000D03*
X127200Y357500D03*
Y352500D03*
Y347500D03*
Y342500D03*
X116900Y418100D03*
Y423100D03*
Y428100D03*
Y433100D03*
X136900D03*
Y428100D03*
Y423100D03*
Y418100D03*
X127200Y763000D03*
Y758000D03*
Y753000D03*
Y748000D03*
X116900Y823600D03*
Y828600D03*
Y833600D03*
Y838600D03*
X136900D03*
Y833600D03*
Y828600D03*
Y823600D03*
X127200Y1168900D03*
Y1163900D03*
Y1158900D03*
Y1153900D03*
X117200Y1229100D03*
Y1234100D03*
Y1239100D03*
Y1244100D03*
X137200D03*
Y1239100D03*
Y1234100D03*
Y1229100D03*
X126700Y1569100D03*
Y1564100D03*
Y1559100D03*
Y1554100D03*
X118400Y1634600D03*
Y1639600D03*
Y1644600D03*
X138400D03*
Y1639600D03*
Y1634600D03*
X118400Y1649600D03*
X138400D03*
X835500Y357500D03*
Y352500D03*
Y347500D03*
Y342500D03*
Y763000D03*
Y758000D03*
Y753000D03*
Y748000D03*
Y1168500D03*
Y1163500D03*
Y1158500D03*
Y1153500D03*
Y1574000D03*
Y1569000D03*
Y1564000D03*
Y1559000D03*
X802439Y1939107D03*
Y1934107D03*
X822439D03*
Y1939107D03*
X802439Y1949107D03*
Y1944107D03*
X822439D03*
Y1949107D03*
X855500Y342500D03*
Y347500D03*
Y352500D03*
Y357500D03*
Y748000D03*
Y753000D03*
Y758000D03*
Y763000D03*
Y1153500D03*
Y1158500D03*
Y1163500D03*
Y1168500D03*
Y1559000D03*
Y1564000D03*
Y1569000D03*
Y1574000D03*
G54D73*
X302953Y1413700D03*
X300984D03*
X299016D03*
X297047D03*
Y1429300D03*
X299016D03*
X300984D03*
X302953D03*
G54D37*
X82087Y28858D03*
Y178464D03*
Y434370D03*
Y583976D03*
Y839882D03*
Y989488D03*
Y1245394D03*
Y1395000D03*
Y1650906D03*
Y1800512D03*
X162008Y191614D03*
Y341220D03*
Y597126D03*
Y746732D03*
Y1002638D03*
Y1152244D03*
Y1408150D03*
Y1557756D03*
Y1813662D03*
Y1963268D03*
X890354Y191614D03*
Y341220D03*
Y597126D03*
Y746732D03*
Y1002638D03*
Y1152244D03*
Y1408150D03*
Y1557756D03*
Y1813662D03*
Y1963268D03*
G54D82*
X822500Y1729750D03*
Y1730250D03*
G54D47*
X59859Y208371D03*
X91200Y344700D03*
X94500Y372700D03*
X67414Y631662D03*
X91200Y750200D03*
X94500Y778200D03*
X77750Y1052836D03*
X91200Y1156100D03*
X94500Y1183700D03*
X76750Y1458550D03*
X90500Y1552200D03*
X83875Y1583575D03*
X77100Y1849600D03*
X61000Y1936200D03*
X56000Y1884200D03*
X41800Y1964000D03*
X180850Y31050D03*
X125700Y51300D03*
X146400Y139700D03*
X150557D03*
X114295Y335017D03*
X153625Y405825D03*
X129975Y404675D03*
X148400Y434300D03*
X120800Y444500D03*
X122025Y573075D03*
X117945Y740617D03*
X148400Y839800D03*
X154000Y811700D03*
X158500Y807700D03*
X130350Y810550D03*
X122251Y848946D03*
X178000Y956200D03*
X117900Y1146000D03*
X148700Y1245300D03*
X154000Y1217200D03*
X130350Y1216050D03*
X121500Y1255500D03*
X130000Y1476700D03*
X122000D03*
X114000D03*
X154000Y1622700D03*
X130350Y1622550D03*
X149900Y1650800D03*
X117000Y1661200D03*
X170080Y1776928D03*
X204500Y32200D03*
X197000Y60200D03*
X203000Y538700D03*
Y546200D03*
Y531200D03*
X194750Y1756450D03*
X200198Y1762200D03*
X305100Y396500D03*
X309300Y404000D03*
X313000Y565700D03*
X292000Y608700D03*
X284000D03*
X304000D03*
X296000D03*
X316000D03*
X308000D03*
X304500Y826000D03*
X308600Y833500D03*
X305200Y1197450D03*
X309300Y1204950D03*
X303500Y1395700D03*
X311500D03*
X287600Y1444700D03*
X279650D03*
X299600D03*
X291600D03*
X311600D03*
X303600D03*
X306200Y1695950D03*
X310300Y1703450D03*
X291500Y1791700D03*
X283500D03*
X275500D03*
X280500Y1734700D03*
X276500D03*
X272500D03*
X352500Y75200D03*
X378100Y88100D03*
X377500Y104700D03*
X344500Y367700D03*
X359500D03*
X340500D03*
X380000D03*
X395000D03*
X355500D03*
X376000D03*
X391000D03*
X398000Y410200D03*
X382500Y454700D03*
X347000D03*
X390500D03*
X355000D03*
X384500Y797700D03*
X388500D03*
X369500D03*
X373500D03*
X382500Y884700D03*
X347000D03*
X390500D03*
X355000D03*
X380000Y1169200D03*
X391000D03*
X395000D03*
X376000D03*
X382500Y1256200D03*
X347000D03*
X390500D03*
X355000D03*
X355500Y1667700D03*
X340500D03*
X359500D03*
X344500D03*
X379000Y1732700D03*
X347000Y1754700D03*
X355000D03*
X429000Y812700D03*
Y820700D03*
Y1215200D03*
Y1223200D03*
Y1713700D03*
Y1721700D03*
X836500Y177700D03*
X828500D03*
X820500D03*
X819500Y344700D03*
X821000Y372700D03*
X819500Y750200D03*
X821000Y778200D03*
X819500Y1155700D03*
X821000Y1183700D03*
X819500Y1561200D03*
X821000Y1589200D03*
X837500Y1791700D03*
X829500D03*
X819000D03*
X784339Y1935207D03*
X769239Y1963207D03*
X866961Y159361D03*
X844050Y334200D03*
X846200Y740200D03*
X844600Y1145600D03*
X845600Y1551200D03*
X906000Y1691200D03*
X859500Y1702700D03*
X902500Y1730700D03*
X898500D03*
X910500Y1731200D03*
X959000Y1671700D03*
G54D83*
X887444Y1709016D03*
Y1710984D03*
X899556D03*
Y1709016D03*
G54D74*
X292200Y1418547D03*
Y1420516D03*
Y1422484D03*
Y1424453D03*
X307800D03*
Y1422484D03*
Y1420516D03*
Y1418547D03*
G54D29*
G01X-106883Y-224955D02*
Y-304955D01*
G01Y-260455D02*
X1019417D01*
G01X-106883Y-304955D02*
X1019417D01*
G01X-110883Y-208955D02*
G02I-12000J0D01*
G01X-116033D02*
G02I-6850J0D01*
G01X-122883Y-224955D02*
Y-192955D01*
G01X-106883Y-208955D02*
X-138883D01*
G01X-106883Y-224955D02*
X1019417D01*
G01X231917D02*
Y-304955D01*
G01X369417Y-224955D02*
Y-304955D01*
G01X484417Y-224955D02*
Y-304955D01*
G01X651917Y-224955D02*
Y-304955D01*
G01X821917Y-224955D02*
Y-304955D01*
G01X1019417Y-224955D02*
Y-304955D01*
G01X1047417Y-208955D02*
G02I-12000J0D01*
G01X1042267D02*
G02I-6850J0D01*
G01X1035417Y-224955D02*
Y-192955D01*
G01X1051417Y-208955D02*
X1019417D01*
X38800Y1810100D03*
X22100Y1802800D03*
X38317Y1804491D03*
X34900Y1807200D03*
X35100Y1813000D03*
X26500Y1805200D03*
X26600Y1810600D03*
X26300Y1815000D03*
X30800Y1805300D03*
Y1810500D03*
X17500Y1801900D03*
X22000Y1814100D03*
Y1809100D03*
X17500Y1806900D03*
Y1811900D03*
Y1816500D03*
X7600Y1855000D03*
X17500Y1827500D03*
X22600Y1825200D03*
X17500Y1832500D03*
X22500Y1830000D03*
X17500Y1837500D03*
X22500Y1835000D03*
X17500Y1842500D03*
X22500Y1840000D03*
X17500Y1847500D03*
X22500Y1845000D03*
X17500Y1852500D03*
X22500Y1850000D03*
X17500Y1857500D03*
X22500Y1855000D03*
Y1865000D03*
X17500Y1867500D03*
X22500Y1860000D03*
X12500Y1845000D03*
Y1850000D03*
Y1855000D03*
Y1840000D03*
X17500Y1872500D03*
X22500Y1870000D03*
X12500D03*
X71200Y36900D03*
X136100Y41200D03*
X302500Y583000D03*
X297500D03*
Y588000D03*
X302500D03*
X300000Y585500D03*
Y1421500D03*
X302500Y1424000D03*
X297500D03*
Y1419000D03*
X302500D03*
X370000Y411000D03*
Y405500D03*
X375500D03*
X381000D03*
X375500Y411000D03*
X381000D03*
X359000D03*
X364500D03*
Y405500D03*
X359000D03*
X370000Y400000D03*
X381000D03*
X375500D03*
X370000Y389000D03*
Y394500D03*
X375500D03*
Y389000D03*
X381000D03*
Y394500D03*
X364500Y400000D03*
X365000Y394500D03*
Y389000D03*
X359000D03*
Y394500D03*
Y400000D03*
X370000Y841000D03*
Y835500D03*
X375500D03*
X381000D03*
X375500Y841000D03*
X381000D03*
X359000D03*
X364500D03*
Y835500D03*
X359000D03*
X370000Y830000D03*
X381000D03*
X375500D03*
X370000Y819000D03*
Y824500D03*
X375500D03*
Y819000D03*
X381000D03*
Y824500D03*
X364500Y830000D03*
X365000Y824500D03*
Y819000D03*
X359000D03*
Y824500D03*
Y830000D03*
X370000Y1212500D03*
Y1207000D03*
X375500D03*
X381000D03*
X375500Y1212500D03*
X381000D03*
X359000D03*
X364500D03*
Y1207000D03*
X359000D03*
X370000Y1201500D03*
X381000D03*
X375500D03*
X370000Y1190500D03*
Y1196000D03*
X375500D03*
Y1190500D03*
X381000D03*
Y1196000D03*
X364500Y1201500D03*
X365000Y1196000D03*
Y1190500D03*
X359000D03*
Y1196000D03*
Y1201500D03*
Y1705500D03*
Y1700000D03*
Y1694500D03*
Y1689000D03*
X365000D03*
Y1694500D03*
X364500Y1700000D03*
Y1705500D03*
Y1711000D03*
X359000D03*
X381000D03*
X375500D03*
X381000Y1705500D03*
X375500D03*
X381000Y1694500D03*
Y1689000D03*
X375500D03*
Y1694500D03*
X370000D03*
Y1689000D03*
Y1705500D03*
Y1711000D03*
X381000Y1700000D03*
X375500D03*
X370000D03*
X891500Y1712000D03*
X895500D03*
Y1708000D03*
X891500D03*
X935000Y1425000D03*
X984900Y1430400D03*
X953800Y1424900D03*
X945000Y1425000D03*
X935000Y1455000D03*
Y1475000D03*
Y1445000D03*
Y1465000D03*
Y1435000D03*
X945000Y1475000D03*
X955000D03*
X965000D03*
X945000Y1465000D03*
X955000D03*
X965000D03*
X945000Y1455000D03*
X955000D03*
X965000D03*
X945000Y1445000D03*
X955000D03*
X965000D03*
X945000Y1435000D03*
X955000D03*
X965000D03*
Y1495000D03*
X955000D03*
X935000Y1485000D03*
Y1495000D03*
X945000D03*
Y1485000D03*
X955000D03*
X965000D03*
X975000Y1495000D03*
Y1485000D03*
Y1475000D03*
Y1465000D03*
Y1455000D03*
Y1445000D03*
Y1435000D03*
X965000Y1525000D03*
X955000D03*
X945000D03*
Y1516000D03*
X955000D03*
X965000D03*
X935000Y1555000D03*
X945000D03*
X955000D03*
X965000D03*
X935000Y1575000D03*
Y1565000D03*
X945000Y1575000D03*
X955000D03*
X965000D03*
Y1565000D03*
X955000D03*
X945000D03*
X935000Y1545000D03*
Y1535000D03*
Y1525000D03*
Y1516000D03*
X965000Y1545000D03*
X955000D03*
X945000D03*
Y1535000D03*
X955000D03*
X965000D03*
X975000Y1565000D03*
Y1575000D03*
Y1525000D03*
Y1535000D03*
Y1545000D03*
Y1555000D03*
X935000Y1505000D03*
X955000D03*
X945000D03*
X965000D03*
Y1605000D03*
X935000Y1595000D03*
Y1585000D03*
X945000Y1595000D03*
X955000D03*
X965000D03*
Y1585000D03*
X955000D03*
X945000D03*
X975000Y1595000D03*
Y1605000D03*
Y1585000D03*
X990600Y1427100D03*
X995000Y1425000D03*
X1005000D03*
G54D56*
X86050Y407200D03*
X67550D03*
X88650Y813200D03*
X70150D03*
X86650Y1218700D03*
X68150D03*
X84950Y1624000D03*
X66450D03*
X160350Y368300D03*
X178850D03*
X160550Y775400D03*
X179050D03*
X160050Y1179500D03*
X178550D03*
X161150Y1585700D03*
X179650D03*
X124950Y1965200D03*
X143450D03*
X889750Y368600D03*
X908250D03*
X889450Y774600D03*
X907950D03*
X893550Y1180600D03*
X912050D03*
X892050Y1584600D03*
X910550D03*
X853250Y1965500D03*
X871750D03*
G54D38*
X105400Y42350D03*
Y23850D03*
G54D92*
X1009744Y1646102D03*
Y1641102D03*
Y1636102D03*
Y1631102D03*
Y1626102D03*
Y1621102D03*
Y1676102D03*
Y1671102D03*
Y1666102D03*
Y1661102D03*
Y1656102D03*
Y1651102D03*
G54D65*
X313700Y416200D03*
Y846700D03*
X313800Y1217500D03*
X314800Y1715700D03*
X969300Y1661000D03*
Y1671000D03*
X925300Y1695000D03*
G54D93*
G01X-90900Y-277455D02*
Y-294955D01*
X-82166D01*
G01X-69033Y-283289D02*
Y-294955D01*
G01Y-278622D02*
X-69470Y-278330D01*
Y-277747D01*
X-69033Y-277455D01*
X-68596Y-277747D01*
Y-278330D01*
X-69033Y-278622D01*
G01X-54590Y-299330D02*
X-53061Y-300497D01*
X-51315Y-300788D01*
X-49787Y-300497D01*
X-48476Y-299039D01*
X-47603Y-296997D01*
Y-283289D01*
G01Y-285622D02*
X-48476Y-284455D01*
X-49787Y-283580D01*
X-51315Y-283289D01*
X-53061Y-283872D01*
X-54153Y-285038D01*
X-55027Y-287080D01*
X-55463Y-289122D01*
X-55245Y-290872D01*
X-54371Y-292914D01*
X-53061Y-294372D01*
X-51315Y-294955D01*
X-50005Y-294663D01*
X-48476Y-293497D01*
X-47603Y-292331D01*
G01X-37745Y-294955D02*
Y-277455D01*
G01Y-285913D02*
X-36653Y-284455D01*
X-35561Y-283580D01*
X-33815Y-283289D01*
X-32505Y-283580D01*
X-30976Y-284747D01*
X-30321Y-286497D01*
Y-294955D01*
G01X-16533Y-277455D02*
Y-294955D01*
G01X-19590Y-283289D02*
X-13476D01*
G01X-2745Y-294955D02*
Y-283289D01*
G01Y-286205D02*
X-1871Y-284747D01*
X-561Y-283580D01*
X1185Y-283289D01*
X2713Y-283580D01*
X4024Y-284747D01*
X4679Y-286788D01*
Y-294955D01*
G01X18467Y-283289D02*
Y-294955D01*
G01Y-278622D02*
X18030Y-278330D01*
Y-277747D01*
X18467Y-277455D01*
X18904Y-277747D01*
Y-278330D01*
X18467Y-278622D01*
G01X32255Y-294955D02*
Y-283289D01*
G01Y-286205D02*
X33129Y-284747D01*
X34439Y-283580D01*
X36185Y-283289D01*
X37713Y-283580D01*
X39024Y-284747D01*
X39679Y-286788D01*
Y-294955D01*
G01X50410Y-299330D02*
X51939Y-300497D01*
X53685Y-300788D01*
X55213Y-300497D01*
X56524Y-299039D01*
X57397Y-296997D01*
Y-283289D01*
G01Y-285622D02*
X56524Y-284455D01*
X55213Y-283580D01*
X53685Y-283289D01*
X51939Y-283872D01*
X50847Y-285038D01*
X49973Y-287080D01*
X49537Y-289122D01*
X49755Y-290872D01*
X50629Y-292914D01*
X51939Y-294372D01*
X53685Y-294955D01*
X54995Y-294663D01*
X56524Y-293497D01*
X57397Y-292331D01*
G01X84100Y-294955D02*
Y-277455D01*
X89340D01*
X91087Y-278330D01*
X92397Y-280372D01*
X92834Y-282705D01*
X92397Y-285038D01*
X91305Y-286788D01*
X89340Y-287664D01*
X84100D01*
G01X101164Y-294955D02*
Y-277455D01*
X105530D01*
X107277Y-278330D01*
X108587Y-279497D01*
X109679Y-281246D01*
X110552Y-283289D01*
X110770Y-286205D01*
X110552Y-289122D01*
X109679Y-291164D01*
X108587Y-292914D01*
X107277Y-294080D01*
X105530Y-294955D01*
X101164D01*
G01X119100D02*
Y-277455D01*
X124340D01*
X126087Y-278330D01*
X127397Y-280372D01*
X127834Y-282705D01*
X127397Y-285038D01*
X126305Y-286788D01*
X124340Y-287664D01*
X119100D01*
G01X142713Y-285622D02*
X143587Y-284747D01*
X144242Y-283289D01*
X144679Y-281246D01*
X144242Y-279497D01*
X143369Y-278330D01*
X141840Y-277455D01*
X135945D01*
Y-294955D01*
X143150D01*
X144679Y-293789D01*
X145552Y-292038D01*
X145989Y-289997D01*
X145552Y-287955D01*
X144242Y-286205D01*
X142713Y-285622D01*
X135945D01*
G01X171600Y-294955D02*
Y-277455D01*
X176840D01*
X178587Y-278330D01*
X179897Y-280372D01*
X180334Y-282705D01*
X179897Y-285038D01*
X178805Y-286788D01*
X176840Y-287664D01*
X171600D01*
G01X188008Y-277455D02*
X193467Y-294955D01*
X198926Y-277455D01*
G01X210967D02*
Y-294955D01*
G01X205945Y-277455D02*
X215989D01*
G01X21540Y-249955D02*
Y-232455D01*
X27217Y-247038D01*
X32894Y-232455D01*
Y-249955D01*
G01X44717D02*
X43407Y-249663D01*
X42097Y-248497D01*
X41223Y-246455D01*
X40787Y-244122D01*
X41223Y-241788D01*
X42097Y-239747D01*
X43407Y-238580D01*
X44717Y-238289D01*
X46027Y-238580D01*
X47337Y-239747D01*
X48210Y-241788D01*
X48429Y-244122D01*
X48210Y-246455D01*
X47337Y-248497D01*
X46027Y-249663D01*
X44717Y-249955D01*
G01X66147Y-232455D02*
Y-249955D01*
G01Y-247331D02*
X65274Y-248789D01*
X63963Y-249663D01*
X62435Y-249955D01*
X60689Y-249372D01*
X59379Y-247914D01*
X58505Y-246164D01*
X58287Y-244122D01*
X58505Y-242080D01*
X59379Y-240330D01*
X60689Y-238872D01*
X62435Y-238289D01*
X63963Y-238580D01*
X65055Y-239164D01*
X66147Y-240330D01*
G01X76442Y-242080D02*
X83429D01*
X82774Y-240038D01*
X81682Y-238872D01*
X80154Y-238289D01*
X78625Y-238580D01*
X77315Y-239455D01*
X76442Y-241497D01*
X76005Y-243247D01*
Y-244997D01*
X76442Y-246747D01*
X77534Y-248497D01*
X78844Y-249663D01*
X80372Y-249955D01*
X81900Y-249372D01*
X83429Y-247622D01*
G01X97217Y-249955D02*
Y-232455D01*
G01X252500Y-249955D02*
Y-232455D01*
X257740D01*
X259487Y-233330D01*
X260797Y-235372D01*
X261234Y-237705D01*
X260797Y-240038D01*
X259705Y-241788D01*
X257740Y-242664D01*
X252500D01*
G01X279170Y-233914D02*
X277860Y-233038D01*
X276332Y-232455D01*
X274585D01*
X272620Y-233330D01*
X271092Y-234788D01*
X270000Y-236539D01*
X269127Y-239455D01*
X268908Y-242080D01*
X269345Y-244705D01*
X270000Y-246455D01*
X271310Y-248205D01*
X272839Y-249372D01*
X274367Y-249955D01*
X275895D01*
X277424Y-249372D01*
X278734Y-248497D01*
X279826Y-247331D01*
G01X293613Y-240622D02*
X294487Y-239747D01*
X295142Y-238289D01*
X295579Y-236246D01*
X295142Y-234497D01*
X294269Y-233330D01*
X292740Y-232455D01*
X286845D01*
Y-249955D01*
X294050D01*
X295579Y-248789D01*
X296452Y-247038D01*
X296889Y-244997D01*
X296452Y-242955D01*
X295142Y-241205D01*
X293613Y-240622D01*
X286845D01*
G01X302817Y-255788D02*
X315917D01*
G01X321845Y-249955D02*
Y-232455D01*
X331889Y-249955D01*
Y-232455D01*
G01X344367Y-249955D02*
X342620Y-249663D01*
X341092Y-248497D01*
X339782Y-246747D01*
X338908Y-244705D01*
X338472Y-242372D01*
Y-240038D01*
X338908Y-237705D01*
X339782Y-235663D01*
X341092Y-233914D01*
X342620Y-232747D01*
X344367Y-232455D01*
X346113Y-232747D01*
X347642Y-233914D01*
X348952Y-235663D01*
X349826Y-237705D01*
X350262Y-240038D01*
Y-242372D01*
X349826Y-244705D01*
X348952Y-246747D01*
X347642Y-248497D01*
X346113Y-249663D01*
X344367Y-249955D01*
G01X265617Y-294955D02*
Y-277455D01*
X262997Y-280955D01*
G01Y-294955D02*
X268237D01*
G01X278314Y-292331D02*
X279623Y-293789D01*
X281152Y-294663D01*
X283117Y-294955D01*
X285082Y-294372D01*
X286610Y-293205D01*
X287702Y-291164D01*
X287920Y-288830D01*
X287484Y-286497D01*
X286392Y-285038D01*
X284863Y-283872D01*
X283335Y-283580D01*
X281807Y-283872D01*
X279842Y-285038D01*
X280497Y-277455D01*
X286392D01*
G01X296469Y-287664D02*
X297997Y-285622D01*
X299307Y-284455D01*
X301054Y-283872D01*
X302582Y-284455D01*
X303674Y-285622D01*
X304547Y-287372D01*
X304765Y-289413D01*
X304547Y-291164D01*
X303674Y-292914D01*
X302363Y-294372D01*
X300835Y-294955D01*
X299089Y-294372D01*
X297560Y-292622D01*
X296687Y-289997D01*
X296469Y-287080D01*
X296905Y-283289D01*
X297560Y-281246D01*
X298652Y-279205D01*
X300180Y-277747D01*
X301709Y-277455D01*
X303237Y-278038D01*
X304329Y-279497D01*
G01X313969Y-287664D02*
X315497Y-285622D01*
X316807Y-284455D01*
X318554Y-283872D01*
X320082Y-284455D01*
X321174Y-285622D01*
X322047Y-287372D01*
X322265Y-289413D01*
X322047Y-291164D01*
X321174Y-292914D01*
X319863Y-294372D01*
X318335Y-294955D01*
X316589Y-294372D01*
X315060Y-292622D01*
X314187Y-289997D01*
X313969Y-287080D01*
X314405Y-283289D01*
X315060Y-281246D01*
X316152Y-279205D01*
X317680Y-277747D01*
X319209Y-277455D01*
X320737Y-278038D01*
X321829Y-279497D01*
G01X331905Y-292914D02*
X333434Y-294372D01*
X335180Y-294955D01*
X336927Y-294372D01*
X338455Y-292622D01*
X339547Y-289997D01*
X339984Y-287372D01*
Y-284164D01*
X339547Y-281539D01*
X338455Y-279205D01*
X337145Y-278038D01*
X335617Y-277455D01*
X333870Y-278038D01*
X332560Y-279205D01*
X331687Y-280955D01*
X331250Y-283289D01*
X331687Y-285330D01*
X332779Y-287372D01*
X334089Y-288539D01*
X335617Y-288830D01*
X337363Y-288247D01*
X338674Y-286788D01*
X339984Y-284164D01*
G01X395208Y-232455D02*
X400667Y-249955D01*
X406126Y-232455D01*
G01X422534Y-249955D02*
X413800D01*
Y-232455D01*
X422534D01*
G01X419040Y-240913D02*
X413800D01*
G01X431300Y-249955D02*
Y-232455D01*
X436759D01*
X438505Y-233330D01*
X439597Y-234497D01*
X440034Y-236830D01*
X439597Y-239164D01*
X438287Y-240622D01*
X436759Y-241497D01*
X431300D01*
G01X436759D02*
X440034Y-249955D01*
G01X453167Y-250538D02*
X452730Y-250247D01*
Y-249663D01*
X453167Y-249372D01*
X453604Y-249663D01*
Y-250247D01*
X453167Y-250538D01*
G01X426917Y-294955D02*
Y-277455D01*
X424297Y-280955D01*
G01Y-294955D02*
X429537D01*
G01X528750Y-232455D02*
Y-249955D01*
X537484D01*
G01X554547D02*
Y-238289D01*
G01Y-240330D02*
X553674Y-239164D01*
X552363Y-238580D01*
X550835Y-238289D01*
X549307Y-238872D01*
X547997Y-240038D01*
X547123Y-241788D01*
X546687Y-244122D01*
X547123Y-246455D01*
X547997Y-248205D01*
X549307Y-249372D01*
X550835Y-249955D01*
X552363Y-249663D01*
X553674Y-248789D01*
X554547Y-247622D01*
G01X563532Y-255205D02*
X564842Y-255788D01*
X566589Y-255205D01*
X567680Y-254039D01*
X568554Y-252580D01*
X569863Y-247914D01*
X572702Y-238289D01*
G01X565715D02*
X569863Y-247914D01*
G01X582342Y-242080D02*
X589329D01*
X588674Y-240038D01*
X587582Y-238872D01*
X586054Y-238289D01*
X584525Y-238580D01*
X583215Y-239455D01*
X582342Y-241497D01*
X581905Y-243247D01*
Y-244997D01*
X582342Y-246747D01*
X583434Y-248497D01*
X584744Y-249663D01*
X586272Y-249955D01*
X587800Y-249372D01*
X589329Y-247622D01*
G01X600060Y-249955D02*
Y-238289D01*
G01Y-240622D02*
X601152Y-239455D01*
X602244Y-238580D01*
X603772Y-238289D01*
X604863Y-238580D01*
X606174Y-239455D01*
G01X533117Y-277455D02*
Y-294955D01*
G01X528095Y-277455D02*
X538139D01*
G01X544940Y-294955D02*
Y-277455D01*
X550617Y-292038D01*
X556294Y-277455D01*
Y-294955D01*
G01X562658D02*
X568117Y-277455D01*
X573576Y-294955D01*
G01X571610Y-288830D02*
X564623D01*
G01X581032Y-292622D02*
X582779Y-294080D01*
X584744Y-294955D01*
X586490D01*
X588237Y-294080D01*
X589547Y-292622D01*
X590202Y-290580D01*
X589765Y-288539D01*
X588674Y-286788D01*
X586709Y-285622D01*
X584089Y-285038D01*
X582560Y-283872D01*
X581905Y-281830D01*
X582342Y-279788D01*
X583434Y-278330D01*
X584962Y-277455D01*
X586490D01*
X588019Y-278038D01*
X589329Y-279497D01*
G01X598314Y-294955D02*
Y-277455D01*
G01X606610D02*
X598314Y-288247D01*
G01X607920Y-294955D02*
X602025Y-283289D01*
G01X670864Y-249955D02*
Y-232455D01*
X675230D01*
X676977Y-233330D01*
X678287Y-234497D01*
X679379Y-236246D01*
X680252Y-238289D01*
X680470Y-241205D01*
X680252Y-244122D01*
X679379Y-246164D01*
X678287Y-247914D01*
X676977Y-249080D01*
X675230Y-249955D01*
X670864D01*
G01X689892Y-242080D02*
X696879D01*
X696224Y-240038D01*
X695132Y-238872D01*
X693604Y-238289D01*
X692075Y-238580D01*
X690765Y-239455D01*
X689892Y-241497D01*
X689455Y-243247D01*
Y-244997D01*
X689892Y-246747D01*
X690984Y-248497D01*
X692294Y-249663D01*
X693822Y-249955D01*
X695350Y-249372D01*
X696879Y-247622D01*
G01X707392Y-247914D02*
X708484Y-249080D01*
X710012Y-249955D01*
X711322D01*
X712632Y-249372D01*
X713505Y-248497D01*
X713942Y-247331D01*
X713724Y-245580D01*
X712850Y-244705D01*
X708920Y-242955D01*
X708047Y-240913D01*
X708484Y-239455D01*
X709357Y-238580D01*
X710667Y-238289D01*
X711977Y-238580D01*
X713287Y-239455D01*
G01X728167Y-238289D02*
Y-249955D01*
G01Y-233622D02*
X727730Y-233330D01*
Y-232747D01*
X728167Y-232455D01*
X728604Y-232747D01*
Y-233330D01*
X728167Y-233622D01*
G01X742610Y-254330D02*
X744139Y-255497D01*
X745885Y-255788D01*
X747413Y-255497D01*
X748724Y-254039D01*
X749597Y-251997D01*
Y-238289D01*
G01Y-240622D02*
X748724Y-239455D01*
X747413Y-238580D01*
X745885Y-238289D01*
X744139Y-238872D01*
X743047Y-240038D01*
X742173Y-242080D01*
X741737Y-244122D01*
X741955Y-245872D01*
X742829Y-247914D01*
X744139Y-249372D01*
X745885Y-249955D01*
X747195Y-249663D01*
X748724Y-248497D01*
X749597Y-247331D01*
G01X759455Y-249955D02*
Y-238289D01*
G01Y-241205D02*
X760329Y-239747D01*
X761639Y-238580D01*
X763385Y-238289D01*
X764913Y-238580D01*
X766224Y-239747D01*
X766879Y-241788D01*
Y-249955D01*
G01X777392Y-242080D02*
X784379D01*
X783724Y-240038D01*
X782632Y-238872D01*
X781104Y-238289D01*
X779575Y-238580D01*
X778265Y-239455D01*
X777392Y-241497D01*
X776955Y-243247D01*
Y-244997D01*
X777392Y-246747D01*
X778484Y-248497D01*
X779794Y-249663D01*
X781322Y-249955D01*
X782850Y-249372D01*
X784379Y-247622D01*
G01X795110Y-249955D02*
Y-238289D01*
G01Y-240622D02*
X796202Y-239455D01*
X797294Y-238580D01*
X798822Y-238289D01*
X799913Y-238580D01*
X801224Y-239455D01*
G01X660367Y-277455D02*
X663423Y-294955D01*
X666917Y-277455D01*
X670410Y-294955D01*
X673467Y-277455D01*
G01X680050Y-294955D02*
Y-277455D01*
X685290D01*
X687037Y-278330D01*
X688347Y-280372D01*
X688784Y-282705D01*
X688347Y-285038D01*
X687255Y-286788D01*
X685290Y-287664D01*
X680050D01*
G01X697332Y-294955D02*
Y-277455D01*
G01X706502D02*
Y-294955D01*
G01Y-286205D02*
X697332D01*
G01X716579Y-289122D02*
X722255D01*
G01X732769Y-294955D02*
Y-277455D01*
X741065D01*
G01X738009Y-285913D02*
X732769D01*
G01X750050Y-277455D02*
Y-294955D01*
X758784D01*
G01X771917D02*
X770170Y-294663D01*
X768642Y-293497D01*
X767332Y-291747D01*
X766458Y-289705D01*
X766022Y-287372D01*
Y-285038D01*
X766458Y-282705D01*
X767332Y-280663D01*
X768642Y-278914D01*
X770170Y-277747D01*
X771917Y-277455D01*
X773663Y-277747D01*
X775192Y-278914D01*
X776502Y-280663D01*
X777376Y-282705D01*
X777812Y-285038D01*
Y-287372D01*
X777376Y-289705D01*
X776502Y-291747D01*
X775192Y-293497D01*
X773663Y-294663D01*
X771917Y-294955D01*
G01X785050D02*
Y-277455D01*
X790509D01*
X792255Y-278330D01*
X793347Y-279497D01*
X793784Y-281830D01*
X793347Y-284164D01*
X792037Y-285622D01*
X790509Y-286497D01*
X785050D01*
G01X790509D02*
X793784Y-294955D01*
G01X801458D02*
X806917Y-277455D01*
X812376Y-294955D01*
G01X810410Y-288830D02*
X803423D01*
G01X841867Y-294955D02*
Y-277455D01*
X839247Y-280955D01*
G01Y-294955D02*
X844487D01*
G01X859367D02*
Y-277455D01*
X856747Y-280955D01*
G01Y-294955D02*
X861987D01*
G01X872937Y-295538D02*
X880797Y-277455D01*
G01X894367Y-294955D02*
Y-277455D01*
X891747Y-280955D01*
G01Y-294955D02*
X896987D01*
G01X907719Y-287664D02*
X909247Y-285622D01*
X910557Y-284455D01*
X912304Y-283872D01*
X913832Y-284455D01*
X914924Y-285622D01*
X915797Y-287372D01*
X916015Y-289413D01*
X915797Y-291164D01*
X914924Y-292914D01*
X913613Y-294372D01*
X912085Y-294955D01*
X910339Y-294372D01*
X908810Y-292622D01*
X907937Y-289997D01*
X907719Y-287080D01*
X908155Y-283289D01*
X908810Y-281246D01*
X909902Y-279205D01*
X911430Y-277747D01*
X912959Y-277455D01*
X914487Y-278038D01*
X915579Y-279497D01*
G01X925437Y-295538D02*
X933297Y-277455D01*
G01X942719Y-280372D02*
X944029Y-278622D01*
X945557Y-277747D01*
X947304Y-277455D01*
X949487Y-278038D01*
X951015Y-279497D01*
X951452Y-281246D01*
X951234Y-282997D01*
X950360Y-284455D01*
X945994Y-287372D01*
X944029Y-289413D01*
X942719Y-292331D01*
X942282Y-294955D01*
X951452D01*
G01X964367Y-277455D02*
X962620Y-278038D01*
X961310Y-279497D01*
X960437Y-281246D01*
X959782Y-283580D01*
X959564Y-286205D01*
X959782Y-288830D01*
X960437Y-291164D01*
X961310Y-292914D01*
X962620Y-294372D01*
X964367Y-294955D01*
X966113Y-294372D01*
X967424Y-292914D01*
X968297Y-291164D01*
X968952Y-288830D01*
X969170Y-286205D01*
X968952Y-283580D01*
X968297Y-281246D01*
X967424Y-279497D01*
X966113Y-278038D01*
X964367Y-277455D01*
G01X981867Y-294955D02*
Y-277455D01*
X979247Y-280955D01*
G01Y-294955D02*
X984487D01*
G01X995219Y-287664D02*
X996747Y-285622D01*
X998057Y-284455D01*
X999804Y-283872D01*
X1001332Y-284455D01*
X1002424Y-285622D01*
X1003297Y-287372D01*
X1003515Y-289413D01*
X1003297Y-291164D01*
X1002424Y-292914D01*
X1001113Y-294372D01*
X999585Y-294955D01*
X997839Y-294372D01*
X996310Y-292622D01*
X995437Y-289997D01*
X995219Y-287080D01*
X995655Y-283289D01*
X996310Y-281246D01*
X997402Y-279205D01*
X998930Y-277747D01*
X1000459Y-277455D01*
X1001987Y-278038D01*
X1003079Y-279497D01*
G01X889564Y-249955D02*
Y-232455D01*
X893930D01*
X895677Y-233330D01*
X896987Y-234497D01*
X898079Y-236246D01*
X898952Y-238289D01*
X899170Y-241205D01*
X898952Y-244122D01*
X898079Y-246164D01*
X896987Y-247914D01*
X895677Y-249080D01*
X893930Y-249955D01*
X889564D01*
G01X915797D02*
Y-238289D01*
G01Y-240330D02*
X914924Y-239164D01*
X913613Y-238580D01*
X912085Y-238289D01*
X910557Y-238872D01*
X909247Y-240038D01*
X908373Y-241788D01*
X907937Y-244122D01*
X908373Y-246455D01*
X909247Y-248205D01*
X910557Y-249372D01*
X912085Y-249955D01*
X913613Y-249663D01*
X914924Y-248789D01*
X915797Y-247622D01*
G01X929367Y-232455D02*
Y-249955D01*
G01X926310Y-238289D02*
X932424D01*
G01X943592Y-242080D02*
X950579D01*
X949924Y-240038D01*
X948832Y-238872D01*
X947304Y-238289D01*
X945775Y-238580D01*
X944465Y-239455D01*
X943592Y-241497D01*
X943155Y-243247D01*
Y-244997D01*
X943592Y-246747D01*
X944684Y-248497D01*
X945994Y-249663D01*
X947522Y-249955D01*
X949050Y-249372D01*
X950579Y-247622D01*
G54D57*
X99600Y411016D03*
Y421984D03*
X106300Y441484D03*
Y430516D03*
X100200Y816216D03*
Y827184D03*
X106300Y846584D03*
Y835616D03*
X106400Y1221916D03*
Y1232884D03*
Y1252284D03*
Y1241316D03*
X107000Y1647016D03*
X100000Y1627416D03*
Y1638384D03*
X107000Y1657984D03*
X109900Y1968184D03*
Y1957216D03*
X97400Y1968184D03*
Y1957216D03*
X139600Y48316D03*
X152100D03*
X139600Y59284D03*
X152100D03*
X137800Y334416D03*
X137900Y365084D03*
Y354116D03*
X137800Y345384D03*
X137900Y770684D03*
Y759716D03*
X137800Y740116D03*
Y751084D03*
X140000Y1175484D03*
Y1164516D03*
X137800Y1145116D03*
Y1156084D03*
X145500Y1571016D03*
X137600Y1550816D03*
Y1561784D03*
X145500Y1581984D03*
X838000Y1967984D03*
Y1957016D03*
X825500Y1967984D03*
Y1957016D03*
X866300Y335016D03*
X874000Y365484D03*
Y354516D03*
X866300Y345984D03*
X874000Y770984D03*
Y760016D03*
X866100Y740316D03*
Y751284D03*
X866000Y1176484D03*
Y1165516D03*
X866200Y1146016D03*
Y1156984D03*
X874500Y1572016D03*
X866300Y1552216D03*
Y1563184D03*
X874500Y1582984D03*
X973200Y1414216D03*
Y1425184D03*
X960700Y1414216D03*
Y1425184D03*
G54D48*
X97731Y241863D03*
Y244423D03*
Y246983D03*
X91231D03*
Y241863D03*
X97731Y647375D03*
Y649935D03*
Y652495D03*
X91231D03*
Y647375D03*
X97731Y1052886D03*
Y1055446D03*
Y1058006D03*
X91231D03*
Y1052886D03*
X97731Y1458398D03*
Y1460958D03*
Y1463518D03*
X91231D03*
Y1458398D03*
X162904Y141013D03*
Y138453D03*
Y135893D03*
X169404D03*
Y141013D03*
X162904Y1356548D03*
Y1353988D03*
Y1351428D03*
X169404D03*
Y1356548D03*
X207596Y1769440D03*
Y1772000D03*
Y1774560D03*
X201096D03*
Y1769440D03*
X898750Y140013D03*
Y134893D03*
X892250D03*
Y137453D03*
Y140013D03*
X897750Y545525D03*
Y540405D03*
X891250D03*
Y542965D03*
Y545525D03*
X897750Y951037D03*
Y945917D03*
X891250D03*
Y948477D03*
Y951037D03*
X897750Y1356548D03*
Y1351428D03*
X891250D03*
Y1353988D03*
Y1356548D03*
Y1762060D03*
Y1759500D03*
Y1756940D03*
X897750D03*
Y1762060D03*
G54D75*
X328600Y1696950D03*
Y1699150D03*
X337800Y397500D03*
Y399700D03*
X336800Y826950D03*
Y829150D03*
X337500Y1198450D03*
Y1200650D03*
G54D66*
X308100Y590421D03*
Y580579D03*
X291900D03*
Y590421D03*
G54D84*
X894484Y1716056D03*
X892516D03*
Y1703944D03*
X894484D03*
G54D39*
X100000Y119200D03*
Y525200D03*
Y930200D03*
Y1335200D03*
Y1749700D03*
X131000Y51000D03*
X144000Y241700D03*
X146600Y357500D03*
X144000Y648200D03*
X146500Y762300D03*
X144000Y1053700D03*
X148500Y1168700D03*
X144000Y1458200D03*
X136700Y1574200D03*
X144000Y1864200D03*
X118500Y1961800D03*
X865500Y357200D03*
X872500Y648200D03*
X865000Y763100D03*
X872500Y1053700D03*
X874500Y1169200D03*
X872500Y1459200D03*
X866000Y1574700D03*
X910500Y1707700D03*
X855000Y1696700D03*
X878000Y1723200D03*
X871500Y1864200D03*
X846500Y1961700D03*
G54D67*
X304921Y577400D03*
X295079D03*
Y593600D03*
X304921D03*
G54D76*
X280840Y1752400D03*
X278280D03*
X275720D03*
X273160D03*
Y1774600D03*
X275720D03*
X278280D03*
X280840D03*
G54D58*
X84700Y357000D03*
Y348000D03*
Y762500D03*
Y753500D03*
Y1168400D03*
Y1159400D03*
X84000Y1564500D03*
Y1555500D03*
X54500Y1939500D03*
Y1948500D03*
X159400Y418600D03*
Y427600D03*
Y824100D03*
Y833100D03*
X159700Y1229600D03*
Y1238600D03*
X160900Y1635100D03*
Y1644100D03*
X208000Y44500D03*
Y53500D03*
X813000Y357000D03*
Y348000D03*
Y762500D03*
Y753500D03*
Y1168000D03*
Y1159000D03*
Y1573500D03*
Y1564500D03*
X777839Y1938507D03*
Y1947507D03*
G54D49*
X99700Y344800D03*
Y750300D03*
Y1156200D03*
X99000Y1552300D03*
X69500Y1936300D03*
X175894Y141463D03*
X145700Y340200D03*
X145800Y745900D03*
X182000Y956300D03*
X145800Y1150400D03*
X175894Y1356598D03*
X145800Y1554100D03*
X133200Y1954500D03*
X373500Y104800D03*
X374300Y88200D03*
X372000Y371300D03*
X368500D03*
X393500Y418300D03*
X343000Y420300D03*
X346500D03*
X362000Y803800D03*
X393500Y848300D03*
X365500Y803800D03*
X343000Y850300D03*
X346500D03*
X367500Y1174800D03*
X371000D03*
X393500Y1225300D03*
X343000Y1221800D03*
X346500D03*
X376000Y1673800D03*
X343000Y1720300D03*
X346500D03*
X372500Y1673800D03*
X828000Y344800D03*
Y750300D03*
Y1155800D03*
Y1561300D03*
X792839Y1935307D03*
X905240Y140063D03*
X874200Y340300D03*
X904240Y545575D03*
X874100Y746800D03*
X904240Y951087D03*
X874100Y1151300D03*
X904240Y1356598D03*
X874200Y1557500D03*
X841500Y1702300D03*
X904240Y1762110D03*
X862500Y1955100D03*
X994600Y1421100D03*
G54D85*
X893500Y1710000D03*
G54D86*
X846557Y1720000D03*
X868443D03*
G54D68*
X307800Y588453D03*
Y586484D03*
Y584516D03*
Y582547D03*
X292200D03*
Y584516D03*
Y586484D03*
Y588453D03*
G54D77*
X354565Y104650D03*
X356530D03*
X358500D03*
X360470D03*
X362435D03*
Y88350D03*
X360470D03*
X358500D03*
X356530D03*
X354565D03*
G54D59*
X108400Y417600D03*
X108700Y823100D03*
X97600Y1229200D03*
X108600Y1633800D03*
X297600Y1401300D03*
X288000Y1751800D03*
X293000D03*
X872500Y250800D03*
X896500Y1690800D03*
X877000Y1700800D03*
X901500Y1690800D03*
X959000Y1627200D03*
X990500Y1422300D03*
G54D87*
X894500Y1730800D03*
Y1727200D03*
G54D78*
X370000Y400000D03*
Y830000D03*
Y1201500D03*
Y1700000D03*
G54D69*
X302953Y577700D03*
X300984D03*
X299016D03*
X297047D03*
Y593300D03*
X299016D03*
X300984D03*
X302953D03*
G54D88*
X983800Y1414300D03*
Y1425300D03*
G54D79*
X352585Y410825D03*
Y408860D03*
Y406890D03*
Y404920D03*
Y402955D03*
Y400985D03*
Y399015D03*
Y397045D03*
Y395080D03*
Y393110D03*
Y391140D03*
Y389175D03*
Y387205D03*
X387415D03*
Y389175D03*
Y391140D03*
Y393110D03*
Y395080D03*
Y397045D03*
Y399015D03*
Y400985D03*
Y402955D03*
Y404920D03*
Y406890D03*
Y408860D03*
Y410825D03*
X352585Y412795D03*
X387415D03*
X352585Y842795D03*
Y840825D03*
Y838860D03*
Y836890D03*
Y834920D03*
Y832955D03*
Y830985D03*
Y829015D03*
Y827045D03*
Y825080D03*
Y823110D03*
Y821140D03*
Y819175D03*
Y817205D03*
X387415D03*
Y819175D03*
Y821140D03*
Y823110D03*
Y825080D03*
Y827045D03*
Y829015D03*
Y830985D03*
Y832955D03*
Y834920D03*
Y836890D03*
Y838860D03*
Y840825D03*
Y842795D03*
X352585Y1210360D03*
Y1208390D03*
Y1206420D03*
Y1204455D03*
Y1202485D03*
Y1200515D03*
Y1198545D03*
Y1196580D03*
Y1194610D03*
Y1192640D03*
Y1190675D03*
Y1188705D03*
X387415D03*
Y1190675D03*
Y1192640D03*
Y1194610D03*
Y1196580D03*
Y1198545D03*
Y1200515D03*
Y1202485D03*
Y1204455D03*
Y1206420D03*
Y1208390D03*
Y1210360D03*
X352585Y1214295D03*
Y1212325D03*
X387415D03*
Y1214295D03*
X352585Y1712795D03*
Y1710825D03*
Y1708860D03*
Y1706890D03*
Y1704920D03*
Y1702955D03*
Y1700985D03*
Y1699015D03*
Y1697045D03*
Y1695080D03*
Y1693110D03*
Y1691140D03*
Y1689175D03*
Y1687205D03*
X387415D03*
Y1689175D03*
Y1691140D03*
Y1693110D03*
Y1695080D03*
Y1697045D03*
Y1699015D03*
Y1700985D03*
Y1702955D03*
Y1704920D03*
Y1706890D03*
Y1708860D03*
Y1710825D03*
Y1712795D03*
G54D89*
X916500Y1725750D03*
M02*
